FILE_TYPE = MACRO_DRAWING;
SET COLOR_WIRE YELLOW;
SET COLOR_PROP ORANGE;
SET COLOR_DOT WHITE;
SET COLOR_ARC YELLOW;
SET COLOR_BODY GREEN;
SET COLOR_NOTE PURPLE;
SET PROP_DISPLAY VALUE;
SET PAGE_NUMBER P173;
FORCEADD Q_RES..2
(-2975 550);
FORCEPROP 1 LAST PART_NUMBER CS11002FB07
J 0
(-2935 425);
DISPLAY 0.638298 (-2935 425);
DISPLAY INVISIBLE (-2935 425);
FORCEPROP 1 LAST MATERIAL CHIP
J 0
(-2935 475);
DISPLAY 0.638298 (-2935 475);
FORCEPROP 1 LAST TOLERANCE 1%
J 0
(-2930 575);
DISPLAY 0.638298 (-2930 575);
FORCEPROP 1 LAST VALUE 100
J 0
(-2930 625);
DISPLAY 0.638298 (-2930 625);
FORCEPROP 1 LAST WATTAGE 1/16W
J 0
(-2935 525);
DISPLAY 0.638298 (-2935 525);
FORCEPROP 1 LAST PACK_TYPE 0402LF
J 0
(-2935 375);
DISPLAY 0.638298 (-2935 375);
FORCEPROP 1 LAST $LOCATION R495
J 0
(-2930 675);
DISPLAY 0.978723 (-2930 675);
FORCEPROP 1 LASTPIN (-2975 650) $PN 1
J 0
(-2970 612);
DISPLAY 0.787234 (-2970 612);
FORCEPROP 1 LASTPIN (-2975 450) $PN 2
J 0
(-2970 460);
DISPLAY 0.787234 (-2970 460);
FORCEPROP 2 LAST CDS_LIB pure_quanta
J 0
(-2975 550);
PAINT MONO (-2975 550);
DISPLAY INVISIBLE (-2975 550);
FORCEPROP 1 LAST PATH I1
J 0
(-2925 725);
DISPLAY 0.978723 (-2925 725);
PAINT WHITE (-2925 725);
DISPLAY INVISIBLE (-2925 725);
FORCEPROP 2 LAST CDS_LOCATION R495
J 0
(-2925 775);
DISPLAY 1.021277 (-2925 775);
DISPLAY INVISIBLE (-2925 775);
FORCEPROP 2 LAST $SEC 1
J 0
(-2925 775);
DISPLAY 0.680851 (-2925 775);
PAINT MONO (-2925 775);
DISPLAY INVISIBLE (-2925 775);
FORCEPROP 2 LAST CDS_SEC 1
J 0
(-2925 775);
DISPLAY 1.021277 (-2925 775);
DISPLAY INVISIBLE (-2925 775);
FORCEADD OFFPAGE..1
(-2450 1275);
FORCEPROP 2 LAST $XR0 190 
J 0
(-2732 1275);
DISPLAY 0.638298 (-2732 1275);
PAINT MONO (-2732 1275);
FORCEPROP 2 LAST CDS_LIB standard
J 0
(-2450 1275);
PAINT MONO (-2450 1275);
DISPLAY INVISIBLE (-2450 1275);
FORCEPROP 1 LAST OFFPAGE TRUE
J 0
(-2125 1150);
DISPLAY 0.872340 (-2125 1150);
DISPLAY INVISIBLE (-2125 1150);
FORCEPROP 1 LAST COMMENT_BODY TRUE
J 0
(-2325 1175);
DISPLAY 0.872340 (-2325 1175);
PAINT GREEN (-2325 1175);
DISPLAY INVISIBLE (-2325 1175);
FORCEPROP 2 LAST PATH I10
J 0
(-2725 1325);
DISPLAY 1.021277 (-2725 1325);
DISPLAY INVISIBLE (-2725 1325);
FORCEADD OFFPAGE..2
(4300 1725);
FORCEPROP 2 LAST $XR0 240 
J 0
(4489 1725);
DISPLAY 0.638298 (4489 1725);
PAINT MONO (4489 1725);
FORCEPROP 2 LAST CDS_LIB standard
J 0
(4300 1725);
PAINT MONO (4300 1725);
DISPLAY INVISIBLE (4300 1725);
FORCEPROP 1 LAST OFFPAGE TRUE
J 0
(4625 1600);
DISPLAY 0.872340 (4625 1600);
DISPLAY INVISIBLE (4625 1600);
FORCEPROP 1 LAST COMMENT_BODY TRUE
J 0
(4255 1630);
DISPLAY 0.872340 (4255 1630);
PAINT GREEN (4255 1630);
DISPLAY INVISIBLE (4255 1630);
FORCEPROP 2 LAST PATH I100
J 0
(4500 1775);
DISPLAY 1.021277 (4500 1775);
DISPLAY INVISIBLE (4500 1775);
FORCEADD OFFPAGE..2
(4300 1875);
FORCEPROP 2 LAST $XR0 169 
J 0
(4489 1875);
DISPLAY 0.638298 (4489 1875);
PAINT MONO (4489 1875);
FORCEPROP 2 LAST CDS_LIB standard
J 0
(4300 1875);
PAINT MONO (4300 1875);
DISPLAY INVISIBLE (4300 1875);
FORCEPROP 1 LAST OFFPAGE TRUE
J 0
(4625 1750);
DISPLAY 0.872340 (4625 1750);
DISPLAY INVISIBLE (4625 1750);
FORCEPROP 1 LAST COMMENT_BODY TRUE
J 0
(4255 1780);
DISPLAY 0.872340 (4255 1780);
PAINT GREEN (4255 1780);
DISPLAY INVISIBLE (4255 1780);
FORCEPROP 2 LAST PATH I101
J 0
(4500 1925);
DISPLAY 1.021277 (4500 1925);
DISPLAY INVISIBLE (4500 1925);
FORCEADD OFFPAGE..2
(4300 1925);
FORCEPROP 2 LAST $XR0 143 
J 0
(4489 1925);
DISPLAY 0.638298 (4489 1925);
PAINT MONO (4489 1925);
FORCEPROP 2 LAST CDS_LIB standard
J 0
(4300 1925);
DISPLAY INVISIBLE (4300 1925);
FORCEPROP 1 LAST OFFPAGE TRUE
J 0
(4625 1800);
DISPLAY 0.872340 (4625 1800);
DISPLAY INVISIBLE (4625 1800);
FORCEPROP 1 LAST COMMENT_BODY TRUE
J 0
(4255 1830);
DISPLAY 0.872340 (4255 1830);
PAINT GREEN (4255 1830);
DISPLAY INVISIBLE (4255 1830);
FORCEPROP 2 LAST PATH I102
J 0
(4500 1975);
DISPLAY 1.021277 (4500 1975);
DISPLAY INVISIBLE (4500 1975);
FORCEADD OFFPAGE..2
(4300 1825);
FORCEPROP 2 LAST $XR0 169 
J 0
(4489 1825);
DISPLAY 0.638298 (4489 1825);
PAINT MONO (4489 1825);
FORCEPROP 1 LAST COMMENT_BODY TRUE
J 0
(4255 1730);
DISPLAY 0.872340 (4255 1730);
PAINT GREEN (4255 1730);
DISPLAY INVISIBLE (4255 1730);
FORCEPROP 1 LAST OFFPAGE TRUE
J 0
(4625 1700);
DISPLAY 0.872340 (4625 1700);
DISPLAY INVISIBLE (4625 1700);
FORCEPROP 2 LAST CDS_LIB standard
J 0
(4300 1825);
PAINT MONO (4300 1825);
DISPLAY INVISIBLE (4300 1825);
FORCEPROP 2 LAST PATH I103
J 0
(4500 1875);
DISPLAY 1.021277 (4500 1875);
DISPLAY INVISIBLE (4500 1875);
FORCEADD OFFPAGE..2
(4300 1775);
FORCEPROP 2 LAST $XR0 240 
J 0
(4489 1775);
DISPLAY 0.638298 (4489 1775);
PAINT MONO (4489 1775);
FORCEPROP 2 LAST CDS_LIB standard
J 0
(4300 1775);
PAINT MONO (4300 1775);
DISPLAY INVISIBLE (4300 1775);
FORCEPROP 1 LAST OFFPAGE TRUE
J 0
(4625 1650);
DISPLAY 0.872340 (4625 1650);
DISPLAY INVISIBLE (4625 1650);
FORCEPROP 1 LAST COMMENT_BODY TRUE
J 0
(4255 1680);
DISPLAY 0.872340 (4255 1680);
PAINT GREEN (4255 1680);
DISPLAY INVISIBLE (4255 1680);
FORCEPROP 2 LAST PATH I104
J 0
(4500 1825);
DISPLAY 1.021277 (4500 1825);
DISPLAY INVISIBLE (4500 1825);
FORCEADD OFFPAGE..2
(4300 1975);
FORCEPROP 2 LAST $XR0 143 
J 0
(4489 1975);
DISPLAY 0.638298 (4489 1975);
PAINT MONO (4489 1975);
FORCEPROP 2 LAST CDS_LIB standard
J 0
(4300 1975);
DISPLAY INVISIBLE (4300 1975);
FORCEPROP 1 LAST OFFPAGE TRUE
J 0
(4625 1850);
DISPLAY 0.872340 (4625 1850);
DISPLAY INVISIBLE (4625 1850);
FORCEPROP 1 LAST COMMENT_BODY TRUE
J 0
(4255 1880);
DISPLAY 0.872340 (4255 1880);
PAINT GREEN (4255 1880);
DISPLAY INVISIBLE (4255 1880);
FORCEPROP 2 LAST PATH I105
J 0
(4500 2025);
DISPLAY 1.021277 (4500 2025);
DISPLAY INVISIBLE (4500 2025);
FORCEADD OFFPAGE..2
(4300 2075);
FORCEPROP 2 LAST $XR0 143 
J 0
(4489 2075);
DISPLAY 0.638298 (4489 2075);
PAINT MONO (4489 2075);
FORCEPROP 2 LAST CDS_LIB standard
J 0
(4300 2075);
DISPLAY INVISIBLE (4300 2075);
FORCEPROP 1 LAST OFFPAGE TRUE
J 0
(4625 1950);
DISPLAY 0.872340 (4625 1950);
DISPLAY INVISIBLE (4625 1950);
FORCEPROP 1 LAST COMMENT_BODY TRUE
J 0
(4255 1980);
DISPLAY 0.872340 (4255 1980);
PAINT GREEN (4255 1980);
DISPLAY INVISIBLE (4255 1980);
FORCEPROP 2 LAST PATH I106
J 0
(4500 2125);
DISPLAY 1.021277 (4500 2125);
DISPLAY INVISIBLE (4500 2125);
FORCEADD OFFPAGE..2
(4300 2025);
FORCEPROP 2 LAST $XR0 143 
J 0
(4489 2025);
DISPLAY 0.638298 (4489 2025);
PAINT MONO (4489 2025);
FORCEPROP 2 LAST CDS_LIB standard
J 0
(4300 2025);
DISPLAY INVISIBLE (4300 2025);
FORCEPROP 1 LAST OFFPAGE TRUE
J 0
(4625 1900);
DISPLAY 0.872340 (4625 1900);
DISPLAY INVISIBLE (4625 1900);
FORCEPROP 1 LAST COMMENT_BODY TRUE
J 0
(4255 1930);
DISPLAY 0.872340 (4255 1930);
PAINT GREEN (4255 1930);
DISPLAY INVISIBLE (4255 1930);
FORCEPROP 2 LAST PATH I107
J 0
(4500 2075);
DISPLAY 1.021277 (4500 2075);
DISPLAY INVISIBLE (4500 2075);
FORCEADD OFFPAGE..2
(3675 3350);
FORCEPROP 2 LAST $XR0 178 
J 0
(3864 3350);
DISPLAY 0.638298 (3864 3350);
PAINT MONO (3864 3350);
FORCEPROP 1 LAST COMMENT_BODY TRUE
J 0
(3630 3255);
DISPLAY 0.872340 (3630 3255);
PAINT GREEN (3630 3255);
DISPLAY INVISIBLE (3630 3255);
FORCEPROP 1 LAST OFFPAGE TRUE
J 0
(4000 3225);
DISPLAY 0.872340 (4000 3225);
PAINT GREEN (4000 3225);
DISPLAY INVISIBLE (4000 3225);
FORCEPROP 2 LAST CDS_LIB standard
J 0
(3675 3350);
DISPLAY INVISIBLE (3675 3350);
FORCEPROP 2 LAST PATH I108
J 0
(3875 3400);
DISPLAY 1.021277 (3875 3400);
DISPLAY INVISIBLE (3875 3400);
FORCEADD OFFPAGE..2
(3675 3300);
FORCEPROP 2 LAST $XR0 178 
J 0
(3864 3300);
DISPLAY 0.638298 (3864 3300);
PAINT MONO (3864 3300);
FORCEPROP 1 LAST COMMENT_BODY TRUE
J 0
(3630 3205);
DISPLAY 0.872340 (3630 3205);
PAINT GREEN (3630 3205);
DISPLAY INVISIBLE (3630 3205);
FORCEPROP 1 LAST OFFPAGE TRUE
J 0
(4000 3175);
DISPLAY 0.872340 (4000 3175);
PAINT GREEN (4000 3175);
DISPLAY INVISIBLE (4000 3175);
FORCEPROP 2 LAST CDS_LIB standard
J 0
(3675 3300);
DISPLAY INVISIBLE (3675 3300);
FORCEPROP 2 LAST PATH I109
J 0
(3875 3350);
DISPLAY 1.021277 (3875 3350);
DISPLAY INVISIBLE (3875 3350);
FORCEADD OFFPAGE..1
(-2450 1225);
FORCEPROP 2 LAST $XR0 190 
J 0
(-2732 1225);
DISPLAY 0.638298 (-2732 1225);
PAINT MONO (-2732 1225);
FORCEPROP 2 LAST CDS_LIB standard
J 0
(-2450 1225);
PAINT MONO (-2450 1225);
DISPLAY INVISIBLE (-2450 1225);
FORCEPROP 1 LAST OFFPAGE TRUE
J 0
(-2125 1100);
DISPLAY 0.872340 (-2125 1100);
DISPLAY INVISIBLE (-2125 1100);
FORCEPROP 1 LAST COMMENT_BODY TRUE
J 0
(-2325 1125);
DISPLAY 0.872340 (-2325 1125);
PAINT GREEN (-2325 1125);
DISPLAY INVISIBLE (-2325 1125);
FORCEPROP 2 LAST PATH I11
J 0
(-2725 1275);
DISPLAY 1.021277 (-2725 1275);
DISPLAY INVISIBLE (-2725 1275);
FORCEADD EMMITSBURG_REV0P9..3
(425 2000);
FORCEPROP 1 LAST PART_NUMBER AJ0QV2N0T00
J 0
(-918 3612);
DISPLAY 0.723404 (-918 3612);
PAINT GREEN (-918 3612);
DISPLAY INVISIBLE (-918 3612);
FORCEPROP 2 LAST PART_TYPE SMLF
J 0
(-900 3850);
DISPLAY 1.021277 (-900 3850);
FORCEPROP 2 LAST VALUE GFNOCPU04302300-QV2N-MM#99A1WT
J 0
(-900 3800);
DISPLAY 1.021277 (-900 3800);
FORCEPROP 1 LAST MATERIAL IC
J 0
(-918 3485);
DISPLAY 0.723404 (-918 3485);
PAINT GREEN (-918 3485);
FORCEPROP 1 LAST $LOCATION U4
J 0
(-918 3759);
DISPLAY 0.723404 (-918 3759);
PAINT GREEN (-918 3759);
FORCEPROP 2 LASTPIN (-1075 3275) $PN A30
J 2
(-1085 3285);
DISPLAY 0.808511 (-1085 3285);
FORCEPROP 2 LASTPIN (-1075 3325) $PN C30
J 2
(-1085 3335);
DISPLAY 0.808511 (-1085 3335);
FORCEPROP 2 LASTPIN (1925 3275) $PN K28
J 0
(1935 3285);
DISPLAY 0.808511 (1935 3285);
FORCEPROP 2 LASTPIN (1925 3325) $PN H28
J 0
(1935 3335);
DISPLAY 0.808511 (1935 3335);
FORCEPROP 2 LASTPIN (-1075 3175) $PN B31
J 2
(-1085 3185);
DISPLAY 0.808511 (-1085 3185);
FORCEPROP 2 LASTPIN (-1075 3225) $PN D31
J 2
(-1085 3235);
DISPLAY 0.808511 (-1085 3235);
FORCEPROP 2 LASTPIN (1925 3175) $PN G29
J 0
(1935 3185);
DISPLAY 0.808511 (1935 3185);
FORCEPROP 2 LASTPIN (1925 3225) $PN F28
J 0
(1935 3235);
DISPLAY 0.808511 (1935 3235);
FORCEPROP 2 LASTPIN (-1075 3075) $PN A32
J 2
(-1085 3085);
DISPLAY 0.808511 (-1085 3085);
FORCEPROP 2 LASTPIN (-1075 3125) $PN C32
J 2
(-1085 3135);
DISPLAY 0.808511 (-1085 3135);
FORCEPROP 2 LASTPIN (1925 3075) $PN J29
J 0
(1935 3085);
DISPLAY 0.808511 (1935 3085);
FORCEPROP 2 LASTPIN (1925 3125) $PN H31
J 0
(1935 3135);
DISPLAY 0.808511 (1935 3135);
FORCEPROP 2 LASTPIN (-1075 2975) $PN B33
J 2
(-1085 2985);
DISPLAY 0.808511 (-1085 2985);
FORCEPROP 2 LASTPIN (-1075 3025) $PN D33
J 2
(-1085 3035);
DISPLAY 0.808511 (-1085 3035);
FORCEPROP 2 LASTPIN (1925 2975) $PN L32
J 0
(1935 2985);
DISPLAY 0.808511 (1935 2985);
FORCEPROP 2 LASTPIN (1925 3025) $PN K31
J 0
(1935 3035);
DISPLAY 0.808511 (1935 3035);
FORCEPROP 2 LASTPIN (-1075 2875) $PN A34
J 2
(-1085 2885);
DISPLAY 0.808511 (-1085 2885);
FORCEPROP 2 LASTPIN (-1075 2925) $PN C34
J 2
(-1085 2935);
DISPLAY 0.808511 (-1085 2935);
FORCEPROP 2 LASTPIN (1925 2875) $PN J32
J 0
(1935 2885);
DISPLAY 0.808511 (1935 2885);
FORCEPROP 2 LASTPIN (1925 2925) $PN G32
J 0
(1935 2935);
DISPLAY 0.808511 (1935 2935);
FORCEPROP 2 LASTPIN (-1075 2775) $PN B35
J 2
(-1085 2785);
DISPLAY 0.808511 (-1085 2785);
FORCEPROP 2 LASTPIN (-1075 2825) $PN D35
J 2
(-1085 2835);
DISPLAY 0.808511 (-1085 2835);
FORCEPROP 2 LASTPIN (1925 2775) $PN G36
J 0
(1935 2785);
DISPLAY 0.808511 (1935 2785);
FORCEPROP 2 LASTPIN (1925 2825) $PN H34
J 0
(1935 2835);
DISPLAY 0.808511 (1935 2835);
FORCEPROP 2 LASTPIN (-1075 2675) $PN A36
J 2
(-1085 2685);
DISPLAY 0.808511 (-1085 2685);
FORCEPROP 2 LASTPIN (-1075 2725) $PN C36
J 2
(-1085 2735);
DISPLAY 0.808511 (-1085 2735);
FORCEPROP 2 LASTPIN (1925 2675) $PN K37
J 0
(1935 2685);
DISPLAY 0.808511 (1935 2685);
FORCEPROP 2 LASTPIN (1925 2725) $PN J36
J 0
(1935 2735);
DISPLAY 0.808511 (1935 2735);
FORCEPROP 2 LASTPIN (-1075 2575) $PN B37
J 2
(-1085 2585);
DISPLAY 0.808511 (-1085 2585);
FORCEPROP 2 LASTPIN (-1075 2625) $PN D37
J 2
(-1085 2635);
DISPLAY 0.808511 (-1085 2635);
FORCEPROP 2 LASTPIN (1925 2575) $PN F37
J 0
(1935 2585);
DISPLAY 0.808511 (1935 2585);
FORCEPROP 2 LASTPIN (1925 2625) $PN H37
J 0
(1935 2635);
DISPLAY 0.808511 (1935 2635);
FORCEPROP 2 LASTPIN (-1075 775) $PN AP31
J 2
(-1085 785);
DISPLAY 0.808511 (-1085 785);
FORCEPROP 2 LASTPIN (-1075 825) $PN AR29
J 2
(-1085 835);
DISPLAY 0.808511 (-1085 835);
FORCEPROP 2 LASTPIN (-1075 675) $PN C40
J 2
(-1085 685);
DISPLAY 0.808511 (-1085 685);
FORCEPROP 2 LASTPIN (-1075 725) $PN D39
J 2
(-1085 735);
DISPLAY 0.808511 (-1085 735);
FORCEPROP 2 LASTPIN (1925 775) $PN N40
J 0
(1935 785);
DISPLAY 0.808511 (1935 785);
FORCEPROP 2 LASTPIN (1925 825) $PN N42
J 0
(1935 835);
DISPLAY 0.808511 (1935 835);
FORCEPROP 2 LASTPIN (-1075 925) $PN AE41
J 2
(-1085 935);
DISPLAY 0.808511 (-1085 935);
FORCEPROP 2 LASTPIN (-1075 975) $PN AE43
J 2
(-1085 985);
DISPLAY 0.808511 (-1085 985);
FORCEPROP 2 LASTPIN (1925 925) $PN AL32
J 0
(1935 935);
DISPLAY 0.808511 (1935 935);
FORCEPROP 2 LASTPIN (1925 975) $PN AK31
J 0
(1935 985);
DISPLAY 0.808511 (1935 985);
FORCEPROP 2 LASTPIN (-1075 1025) $PN AD40
J 2
(-1085 1035);
DISPLAY 0.808511 (-1085 1035);
FORCEPROP 2 LASTPIN (-1075 1075) $PN AD42
J 2
(-1085 1085);
DISPLAY 0.808511 (-1085 1085);
FORCEPROP 2 LASTPIN (1925 1025) $PN AN36
J 0
(1935 1035);
DISPLAY 0.808511 (1935 1035);
FORCEPROP 2 LASTPIN (1925 1075) $PN AP34
J 0
(1935 1085);
DISPLAY 0.808511 (1935 1085);
FORCEPROP 2 LASTPIN (-1075 1125) $PN AC41
J 2
(-1085 1135);
DISPLAY 0.808511 (-1085 1135);
FORCEPROP 2 LASTPIN (-1075 1175) $PN AC43
J 2
(-1085 1185);
DISPLAY 0.808511 (-1085 1185);
FORCEPROP 2 LASTPIN (1925 1125) $PN AR36
J 0
(1935 1135);
DISPLAY 0.808511 (1935 1135);
FORCEPROP 2 LASTPIN (1925 1175) $PN AT37
J 0
(1935 1185);
DISPLAY 0.808511 (1935 1185);
FORCEPROP 2 LASTPIN (-1075 1225) $PN AB40
J 2
(-1085 1235);
DISPLAY 0.808511 (-1085 1235);
FORCEPROP 2 LASTPIN (-1075 1275) $PN AB42
J 2
(-1085 1285);
DISPLAY 0.808511 (-1085 1285);
FORCEPROP 2 LASTPIN (1925 1225) $PN AK34
J 0
(1935 1235);
DISPLAY 0.808511 (1935 1235);
FORCEPROP 2 LASTPIN (1925 1275) $PN AM34
J 0
(1935 1285);
DISPLAY 0.808511 (1935 1285);
FORCEPROP 2 LASTPIN (-1075 1325) $PN AA41
J 2
(-1085 1335);
DISPLAY 0.808511 (-1085 1335);
FORCEPROP 2 LASTPIN (-1075 1375) $PN AA43
J 2
(-1085 1385);
DISPLAY 0.808511 (-1085 1385);
FORCEPROP 2 LASTPIN (1925 1325) $PN AL36
J 0
(1935 1335);
DISPLAY 0.808511 (1935 1335);
FORCEPROP 2 LASTPIN (1925 1375) $PN AM37
J 0
(1935 1385);
DISPLAY 0.808511 (1935 1385);
FORCEPROP 2 LASTPIN (-1075 1425) $PN Y40
J 2
(-1085 1435);
DISPLAY 0.808511 (-1085 1435);
FORCEPROP 2 LASTPIN (-1075 1475) $PN Y42
J 2
(-1085 1485);
DISPLAY 0.808511 (-1085 1485);
FORCEPROP 2 LASTPIN (1925 1425) $PN AH34
J 0
(1935 1435);
DISPLAY 0.808511 (1935 1435);
FORCEPROP 2 LASTPIN (1925 1475) $PN AJ32
J 0
(1935 1485);
DISPLAY 0.808511 (1935 1485);
FORCEPROP 2 LASTPIN (-1075 1525) $PN W41
J 2
(-1085 1535);
DISPLAY 0.808511 (-1085 1535);
FORCEPROP 2 LASTPIN (-1075 1575) $PN W43
J 2
(-1085 1585);
DISPLAY 0.808511 (-1085 1585);
FORCEPROP 2 LASTPIN (1925 1525) $PN AF37
J 0
(1935 1535);
DISPLAY 0.808511 (1935 1535);
FORCEPROP 2 LASTPIN (1925 1575) $PN AH37
J 0
(1935 1585);
DISPLAY 0.808511 (1935 1585);
FORCEPROP 2 LASTPIN (-1075 1625) $PN V40
J 2
(-1085 1635);
DISPLAY 0.808511 (-1085 1635);
FORCEPROP 2 LASTPIN (-1075 1675) $PN V42
J 2
(-1085 1685);
DISPLAY 0.808511 (-1085 1685);
FORCEPROP 2 LASTPIN (1925 1625) $PN AF34
J 0
(1935 1635);
DISPLAY 0.808511 (1935 1635);
FORCEPROP 2 LASTPIN (1925 1675) $PN AG36
J 0
(1935 1685);
DISPLAY 0.808511 (1935 1685);
FORCEPROP 2 LASTPIN (-1075 1725) $PN U41
J 2
(-1085 1735);
DISPLAY 0.808511 (-1085 1735);
FORCEPROP 2 LASTPIN (-1075 1775) $PN U43
J 2
(-1085 1785);
DISPLAY 0.808511 (-1085 1785);
FORCEPROP 2 LASTPIN (1925 1725) $PN AE36
J 0
(1935 1735);
DISPLAY 0.808511 (1935 1735);
FORCEPROP 2 LASTPIN (1925 1775) $PN AD37
J 0
(1935 1785);
DISPLAY 0.808511 (1935 1785);
FORCEPROP 2 LASTPIN (-1075 1825) $PN R40
J 2
(-1085 1835);
DISPLAY 0.808511 (-1085 1835);
FORCEPROP 2 LASTPIN (-1075 1875) $PN R42
J 2
(-1085 1885);
DISPLAY 0.808511 (-1085 1885);
FORCEPROP 2 LASTPIN (1925 1825) $PN AE32
J 0
(1935 1835);
DISPLAY 0.808511 (1935 1835);
FORCEPROP 2 LASTPIN (1925 1875) $PN AG32
J 0
(1935 1885);
DISPLAY 0.808511 (1935 1885);
FORCEPROP 2 LASTPIN (-1075 1925) $PN M41
J 2
(-1085 1935);
DISPLAY 0.808511 (-1085 1935);
FORCEPROP 2 LASTPIN (-1075 1975) $PN M43
J 2
(-1085 1985);
DISPLAY 0.808511 (-1085 1985);
FORCEPROP 2 LASTPIN (1925 1925) $PN W36
J 0
(1935 1935);
DISPLAY 0.808511 (1935 1935);
FORCEPROP 2 LASTPIN (1925 1975) $PN Y37
J 0
(1935 1985);
DISPLAY 0.808511 (1935 1985);
FORCEPROP 2 LASTPIN (-1075 2025) $PN L40
J 2
(-1085 2035);
DISPLAY 0.808511 (-1085 2035);
FORCEPROP 2 LASTPIN (-1075 2075) $PN L42
J 2
(-1085 2085);
DISPLAY 0.808511 (-1085 2085);
FORCEPROP 2 LASTPIN (1925 2025) $PN T37
J 0
(1935 2035);
DISPLAY 0.808511 (1935 2035);
FORCEPROP 2 LASTPIN (1925 2075) $PN V37
J 0
(1935 2085);
DISPLAY 0.808511 (1935 2085);
FORCEPROP 2 LASTPIN (-1075 2125) $PN K41
J 2
(-1085 2135);
DISPLAY 0.808511 (-1085 2135);
FORCEPROP 2 LASTPIN (-1075 2175) $PN K43
J 2
(-1085 2185);
DISPLAY 0.808511 (-1085 2185);
FORCEPROP 2 LASTPIN (1925 2125) $PN V34
J 0
(1935 2135);
DISPLAY 0.808511 (1935 2135);
FORCEPROP 2 LASTPIN (1925 2175) $PN U36
J 0
(1935 2185);
DISPLAY 0.808511 (1935 2185);
FORCEPROP 2 LASTPIN (-1075 2225) $PN J40
J 2
(-1085 2235);
DISPLAY 0.808511 (-1085 2235);
FORCEPROP 2 LASTPIN (-1075 2275) $PN J42
J 2
(-1085 2285);
DISPLAY 0.808511 (-1085 2285);
FORCEPROP 2 LASTPIN (1925 2225) $PN U32
J 0
(1935 2235);
DISPLAY 0.808511 (1935 2235);
FORCEPROP 2 LASTPIN (1925 2275) $PN W32
J 0
(1935 2285);
DISPLAY 0.808511 (1935 2285);
FORCEPROP 2 LASTPIN (-1075 2325) $PN H41
J 2
(-1085 2335);
DISPLAY 0.808511 (-1085 2335);
FORCEPROP 2 LASTPIN (-1075 2375) $PN H43
J 2
(-1085 2385);
DISPLAY 0.808511 (-1085 2385);
FORCEPROP 2 LASTPIN (1925 2325) $PN R32
J 0
(1935 2335);
DISPLAY 0.808511 (1935 2335);
FORCEPROP 2 LASTPIN (1925 2375) $PN T34
J 0
(1935 2385);
DISPLAY 0.808511 (1935 2385);
FORCEPROP 2 LASTPIN (-1075 2425) $PN G40
J 2
(-1085 2435);
DISPLAY 0.808511 (-1085 2435);
FORCEPROP 2 LASTPIN (-1075 2475) $PN G42
J 2
(-1085 2485);
DISPLAY 0.808511 (-1085 2485);
FORCEPROP 2 LASTPIN (1925 2425) $PN P34
J 0
(1935 2435);
DISPLAY 0.808511 (1935 2435);
FORCEPROP 2 LASTPIN (1925 2475) $PN N36
J 0
(1935 2485);
DISPLAY 0.808511 (1935 2485);
FORCEPROP 1 LAST NEEDS_NO_SIZE TRUE
J 0
(425 2000);
DISPLAY 0.723404 (425 2000);
PAINT GREEN (425 2000);
DISPLAY INVISIBLE (425 2000);
FORCEPROP 1 LAST CDS_LMAN_SYM_OUTLINE -1350,1475,1350,-1475
J 0
(425 2000);
DISPLAY 0.468085 (425 2000);
PAINT GREEN (425 2000);
DISPLAY INVISIBLE (425 2000);
FORCEPROP 2 LAST CDS_LIB pure_quanta
J 0
(425 2000);
PAINT MONO (425 2000);
DISPLAY INVISIBLE (425 2000);
FORCEPROP 1 LAST PATH I110
J 0
(425 2000);
DISPLAY 0.723404 (425 2000);
PAINT GREEN (425 2000);
DISPLAY INVISIBLE (425 2000);
FORCEPROP 2 LAST CDS_LOCATION U4
J 0
(-925 3650);
DISPLAY 1.021277 (-925 3650);
DISPLAY INVISIBLE (-925 3650);
FORCEPROP 2 LAST $SEC 3
J 0
(-900 3900);
DISPLAY 0.680851 (-900 3900);
PAINT MONO (-900 3900);
DISPLAY INVISIBLE (-900 3900);
FORCEPROP 2 LAST CDS_SEC 3
J 0
(-925 3650);
DISPLAY 1.021277 (-925 3650);
DISPLAY INVISIBLE (-925 3650);
FORCEADD OFFPAGE..1
(-2450 1425);
FORCEPROP 2 LAST $XR0 191 
J 0
(-2732 1425);
DISPLAY 0.638298 (-2732 1425);
PAINT MONO (-2732 1425);
FORCEPROP 1 LAST COMMENT_BODY TRUE
J 0
(-2325 1325);
DISPLAY 0.872340 (-2325 1325);
PAINT GREEN (-2325 1325);
DISPLAY INVISIBLE (-2325 1325);
FORCEPROP 1 LAST OFFPAGE TRUE
J 0
(-2125 1300);
DISPLAY 0.872340 (-2125 1300);
DISPLAY INVISIBLE (-2125 1300);
FORCEPROP 2 LAST CDS_LIB standard
J 0
(-2450 1425);
PAINT MONO (-2450 1425);
DISPLAY INVISIBLE (-2450 1425);
FORCEPROP 2 LAST PATH I12
J 0
(-2725 1475);
DISPLAY 1.021277 (-2725 1475);
DISPLAY INVISIBLE (-2725 1475);
FORCEADD OFFPAGE..1
(-2450 1525);
FORCEPROP 2 LAST $XR0 191 
J 0
(-2732 1525);
DISPLAY 0.638298 (-2732 1525);
PAINT MONO (-2732 1525);
FORCEPROP 1 LAST COMMENT_BODY TRUE
J 0
(-2325 1425);
DISPLAY 0.872340 (-2325 1425);
PAINT GREEN (-2325 1425);
DISPLAY INVISIBLE (-2325 1425);
FORCEPROP 1 LAST OFFPAGE TRUE
J 0
(-2125 1400);
DISPLAY 0.872340 (-2125 1400);
DISPLAY INVISIBLE (-2125 1400);
FORCEPROP 2 LAST CDS_LIB standard
J 0
(-2450 1525);
PAINT MONO (-2450 1525);
DISPLAY INVISIBLE (-2450 1525);
FORCEPROP 2 LAST PATH I13
J 0
(-2725 1575);
DISPLAY 1.021277 (-2725 1575);
DISPLAY INVISIBLE (-2725 1575);
FORCEADD OFFPAGE..1
(-2450 1475);
FORCEPROP 2 LAST $XR0 191 
J 0
(-2732 1475);
DISPLAY 0.638298 (-2732 1475);
PAINT MONO (-2732 1475);
FORCEPROP 1 LAST COMMENT_BODY TRUE
J 0
(-2325 1375);
DISPLAY 0.872340 (-2325 1375);
PAINT GREEN (-2325 1375);
DISPLAY INVISIBLE (-2325 1375);
FORCEPROP 1 LAST OFFPAGE TRUE
J 0
(-2125 1350);
DISPLAY 0.872340 (-2125 1350);
DISPLAY INVISIBLE (-2125 1350);
FORCEPROP 2 LAST CDS_LIB standard
J 0
(-2450 1475);
PAINT MONO (-2450 1475);
DISPLAY INVISIBLE (-2450 1475);
FORCEPROP 2 LAST PATH I14
J 0
(-2725 1525);
DISPLAY 1.021277 (-2725 1525);
DISPLAY INVISIBLE (-2725 1525);
FORCEADD OFFPAGE..1
(-2450 1575);
FORCEPROP 2 LAST $XR0 191 
J 0
(-2732 1575);
DISPLAY 0.638298 (-2732 1575);
PAINT MONO (-2732 1575);
FORCEPROP 1 LAST COMMENT_BODY TRUE
J 0
(-2325 1475);
DISPLAY 0.872340 (-2325 1475);
PAINT GREEN (-2325 1475);
DISPLAY INVISIBLE (-2325 1475);
FORCEPROP 1 LAST OFFPAGE TRUE
J 0
(-2125 1450);
DISPLAY 0.872340 (-2125 1450);
DISPLAY INVISIBLE (-2125 1450);
FORCEPROP 2 LAST CDS_LIB standard
J 0
(-2450 1575);
PAINT MONO (-2450 1575);
DISPLAY INVISIBLE (-2450 1575);
FORCEPROP 2 LAST PATH I15
J 0
(-2725 1625);
DISPLAY 1.021277 (-2725 1625);
DISPLAY INVISIBLE (-2725 1625);
FORCEADD OFFPAGE..1
(-2450 1625);
FORCEPROP 2 LAST $XR0 191 
J 0
(-2732 1625);
DISPLAY 0.638298 (-2732 1625);
PAINT MONO (-2732 1625);
FORCEPROP 1 LAST COMMENT_BODY TRUE
J 0
(-2325 1525);
DISPLAY 0.872340 (-2325 1525);
PAINT GREEN (-2325 1525);
DISPLAY INVISIBLE (-2325 1525);
FORCEPROP 1 LAST OFFPAGE TRUE
J 0
(-2125 1500);
DISPLAY 0.872340 (-2125 1500);
DISPLAY INVISIBLE (-2125 1500);
FORCEPROP 2 LAST CDS_LIB standard
J 0
(-2450 1625);
PAINT MONO (-2450 1625);
DISPLAY INVISIBLE (-2450 1625);
FORCEPROP 2 LAST PATH I16
J 0
(-2725 1675);
DISPLAY 1.021277 (-2725 1675);
DISPLAY INVISIBLE (-2725 1675);
FORCEADD OFFPAGE..1
(-2450 1675);
FORCEPROP 2 LAST $XR0 191 
J 0
(-2732 1675);
DISPLAY 0.638298 (-2732 1675);
PAINT MONO (-2732 1675);
FORCEPROP 1 LAST COMMENT_BODY TRUE
J 0
(-2325 1575);
DISPLAY 0.872340 (-2325 1575);
PAINT GREEN (-2325 1575);
DISPLAY INVISIBLE (-2325 1575);
FORCEPROP 1 LAST OFFPAGE TRUE
J 0
(-2125 1550);
DISPLAY 0.872340 (-2125 1550);
DISPLAY INVISIBLE (-2125 1550);
FORCEPROP 2 LAST CDS_LIB standard
J 0
(-2450 1675);
PAINT MONO (-2450 1675);
DISPLAY INVISIBLE (-2450 1675);
FORCEPROP 2 LAST PATH I17
J 0
(-2725 1725);
DISPLAY 1.021277 (-2725 1725);
DISPLAY INVISIBLE (-2725 1725);
FORCEADD OFFPAGE..1
(-2450 1725);
FORCEPROP 2 LAST $XR0 240 
J 0
(-2732 1725);
DISPLAY 0.638298 (-2732 1725);
PAINT MONO (-2732 1725);
FORCEPROP 1 LAST OFFPAGE TRUE
J 0
(-2125 1600);
DISPLAY 0.872340 (-2125 1600);
DISPLAY INVISIBLE (-2125 1600);
FORCEPROP 1 LAST COMMENT_BODY TRUE
J 0
(-2325 1625);
DISPLAY 0.872340 (-2325 1625);
PAINT GREEN (-2325 1625);
DISPLAY INVISIBLE (-2325 1625);
FORCEPROP 2 LAST CDS_LIB standard
J 0
(-2450 1725);
PAINT MONO (-2450 1725);
DISPLAY INVISIBLE (-2450 1725);
FORCEPROP 2 LAST PATH I18
J 0
(-2725 1775);
DISPLAY 1.021277 (-2725 1775);
DISPLAY INVISIBLE (-2725 1775);
FORCEADD OFFPAGE..1
(-2450 1775);
FORCEPROP 2 LAST $XR0 240 
J 0
(-2732 1775);
DISPLAY 0.638298 (-2732 1775);
PAINT MONO (-2732 1775);
FORCEPROP 1 LAST OFFPAGE TRUE
J 0
(-2125 1650);
DISPLAY 0.872340 (-2125 1650);
DISPLAY INVISIBLE (-2125 1650);
FORCEPROP 1 LAST COMMENT_BODY TRUE
J 0
(-2325 1675);
DISPLAY 0.872340 (-2325 1675);
PAINT GREEN (-2325 1675);
DISPLAY INVISIBLE (-2325 1675);
FORCEPROP 2 LAST CDS_LIB standard
J 0
(-2450 1775);
PAINT MONO (-2450 1775);
DISPLAY INVISIBLE (-2450 1775);
FORCEPROP 2 LAST PATH I19
J 0
(-2725 1825);
DISPLAY 1.021277 (-2725 1825);
DISPLAY INVISIBLE (-2725 1825);
FORCEADD OFFPAGE..1
(-2450 925);
FORCEPROP 2 LAST $XR0 190 
J 0
(-2732 925);
DISPLAY 0.638298 (-2732 925);
PAINT MONO (-2732 925);
FORCEPROP 2 LAST CDS_LIB standard
J 0
(-2450 925);
PAINT MONO (-2450 925);
DISPLAY INVISIBLE (-2450 925);
FORCEPROP 1 LAST OFFPAGE TRUE
J 0
(-2125 800);
DISPLAY 0.872340 (-2125 800);
DISPLAY INVISIBLE (-2125 800);
FORCEPROP 1 LAST COMMENT_BODY TRUE
J 0
(-2325 825);
DISPLAY 0.872340 (-2325 825);
PAINT GREEN (-2325 825);
DISPLAY INVISIBLE (-2325 825);
FORCEPROP 2 LAST PATH I2
J 0
(-2725 975);
DISPLAY 1.021277 (-2725 975);
DISPLAY INVISIBLE (-2725 975);
FORCEADD OFFPAGE..1
(-2450 1825);
FORCEPROP 2 LAST $XR0 169 
J 0
(-2732 1825);
DISPLAY 0.638298 (-2732 1825);
PAINT MONO (-2732 1825);
FORCEPROP 1 LAST COMMENT_BODY TRUE
J 0
(-2325 1725);
DISPLAY 0.872340 (-2325 1725);
PAINT GREEN (-2325 1725);
DISPLAY INVISIBLE (-2325 1725);
FORCEPROP 1 LAST OFFPAGE TRUE
J 0
(-2125 1700);
DISPLAY 0.872340 (-2125 1700);
DISPLAY INVISIBLE (-2125 1700);
FORCEPROP 2 LAST CDS_LIB standard
J 0
(-2450 1825);
DISPLAY INVISIBLE (-2450 1825);
FORCEPROP 2 LAST PATH I20
J 0
(-2725 1875);
DISPLAY 1.021277 (-2725 1875);
DISPLAY INVISIBLE (-2725 1875);
FORCEADD OFFPAGE..1
(-2450 1925);
FORCEPROP 2 LAST $XR0 143 
J 0
(-2732 1925);
DISPLAY 0.638298 (-2732 1925);
PAINT MONO (-2732 1925);
FORCEPROP 2 LAST CDS_LIB standard
J 0
(-2450 1925);
DISPLAY INVISIBLE (-2450 1925);
FORCEPROP 1 LAST COMMENT_BODY TRUE
J 0
(-2325 1825);
DISPLAY 0.872340 (-2325 1825);
PAINT GREEN (-2325 1825);
DISPLAY INVISIBLE (-2325 1825);
FORCEPROP 1 LAST OFFPAGE TRUE
J 0
(-2125 1800);
DISPLAY 0.872340 (-2125 1800);
DISPLAY INVISIBLE (-2125 1800);
FORCEPROP 2 LAST PATH I21
J 0
(-2725 1975);
DISPLAY 1.021277 (-2725 1975);
DISPLAY INVISIBLE (-2725 1975);
FORCEADD OFFPAGE..1
(-2450 1875);
FORCEPROP 2 LAST $XR0 169 
J 0
(-2732 1875);
DISPLAY 0.638298 (-2732 1875);
PAINT MONO (-2732 1875);
FORCEPROP 1 LAST COMMENT_BODY TRUE
J 0
(-2325 1775);
DISPLAY 0.872340 (-2325 1775);
PAINT GREEN (-2325 1775);
DISPLAY INVISIBLE (-2325 1775);
FORCEPROP 1 LAST OFFPAGE TRUE
J 0
(-2125 1750);
DISPLAY 0.872340 (-2125 1750);
DISPLAY INVISIBLE (-2125 1750);
FORCEPROP 2 LAST CDS_LIB standard
J 0
(-2450 1875);
DISPLAY INVISIBLE (-2450 1875);
FORCEPROP 2 LAST PATH I22
J 0
(-2725 1925);
DISPLAY 1.021277 (-2725 1925);
DISPLAY INVISIBLE (-2725 1925);
FORCEADD OFFPAGE..1
(-2450 1975);
FORCEPROP 2 LAST $XR0 143 
J 0
(-2732 1975);
DISPLAY 0.638298 (-2732 1975);
PAINT MONO (-2732 1975);
FORCEPROP 2 LAST CDS_LIB standard
J 0
(-2450 1975);
DISPLAY INVISIBLE (-2450 1975);
FORCEPROP 1 LAST COMMENT_BODY TRUE
J 0
(-2325 1875);
DISPLAY 0.872340 (-2325 1875);
PAINT GREEN (-2325 1875);
DISPLAY INVISIBLE (-2325 1875);
FORCEPROP 1 LAST OFFPAGE TRUE
J 0
(-2125 1850);
DISPLAY 0.872340 (-2125 1850);
DISPLAY INVISIBLE (-2125 1850);
FORCEPROP 2 LAST PATH I23
J 0
(-2725 2025);
DISPLAY 1.021277 (-2725 2025);
DISPLAY INVISIBLE (-2725 2025);
FORCEADD OFFPAGE..1
(-2450 2075);
FORCEPROP 2 LAST $XR0 143 
J 0
(-2732 2075);
DISPLAY 0.638298 (-2732 2075);
PAINT MONO (-2732 2075);
FORCEPROP 2 LAST CDS_LIB standard
J 0
(-2450 2075);
DISPLAY INVISIBLE (-2450 2075);
FORCEPROP 1 LAST COMMENT_BODY TRUE
J 0
(-2325 1975);
DISPLAY 0.872340 (-2325 1975);
PAINT GREEN (-2325 1975);
DISPLAY INVISIBLE (-2325 1975);
FORCEPROP 1 LAST OFFPAGE TRUE
J 0
(-2125 1950);
DISPLAY 0.872340 (-2125 1950);
DISPLAY INVISIBLE (-2125 1950);
FORCEPROP 2 LAST PATH I24
J 0
(-2725 2125);
DISPLAY 1.021277 (-2725 2125);
DISPLAY INVISIBLE (-2725 2125);
FORCEADD OFFPAGE..1
(-2450 2025);
FORCEPROP 2 LAST $XR0 143 
J 0
(-2732 2025);
DISPLAY 0.638298 (-2732 2025);
PAINT MONO (-2732 2025);
FORCEPROP 2 LAST CDS_LIB standard
J 0
(-2450 2025);
DISPLAY INVISIBLE (-2450 2025);
FORCEPROP 1 LAST COMMENT_BODY TRUE
J 0
(-2325 1925);
DISPLAY 0.872340 (-2325 1925);
PAINT GREEN (-2325 1925);
DISPLAY INVISIBLE (-2325 1925);
FORCEPROP 1 LAST OFFPAGE TRUE
J 0
(-2125 1900);
DISPLAY 0.872340 (-2125 1900);
DISPLAY INVISIBLE (-2125 1900);
FORCEPROP 2 LAST PATH I25
J 0
(-2725 2075);
DISPLAY 1.021277 (-2725 2075);
DISPLAY INVISIBLE (-2725 2075);
FORCEADD TAP..1
R 2
(-1625 2625);
FORCEPROP 3 LASTPIN (-1575 2625) SIG_NAME DMI_CPU0_PCH_TX_C_DP<7>
J 0
(-1565 2635);
DISPLAY 0.659574 (-1565 2635);
PAINT MONO (-1565 2635);
DISPLAY INVISIBLE (-1565 2635);
FORCEPROP 1 LASTPIN (-1575 2625) BN 7
J 2
(-1563 2633);
DISPLAY 0.680851 (-1563 2633);
PAINT GREEN (-1563 2633);
FORCEPROP 1 LAST HDL_TAP TRUE
J 2
(-1950 2500);
DISPLAY 0.872340 (-1950 2500);
PAINT GREEN (-1950 2500);
DISPLAY INVISIBLE (-1950 2500);
FORCEPROP 1 LAST BODY_TYPE PLUMBING
J 2
(-1625 2675);
DISPLAY 0.872340 (-1625 2675);
PAINT GREEN (-1625 2675);
DISPLAY INVISIBLE (-1625 2675);
FORCEPROP 2 LAST CDS_LIB standard
J 0
(-1625 2625);
DISPLAY INVISIBLE (-1625 2625);
FORCEPROP 1 LAST PATH I26
J 2
(-1623 2625);
DISPLAY 0.872340 (-1623 2625);
PAINT GREEN (-1623 2625);
DISPLAY INVISIBLE (-1623 2625);
FORCEADD TAP..1
R 2
(-1475 2575);
FORCEPROP 3 LASTPIN (-1425 2575) SIG_NAME DMI_CPU0_PCH_TX_C_DN<7>
J 0
(-1415 2585);
DISPLAY 0.659574 (-1415 2585);
PAINT MONO (-1415 2585);
DISPLAY INVISIBLE (-1415 2585);
FORCEPROP 1 LASTPIN (-1425 2575) BN 7
J 2
(-1413 2583);
DISPLAY 0.680851 (-1413 2583);
PAINT GREEN (-1413 2583);
FORCEPROP 1 LAST HDL_TAP TRUE
J 2
(-1800 2450);
DISPLAY 0.872340 (-1800 2450);
PAINT GREEN (-1800 2450);
DISPLAY INVISIBLE (-1800 2450);
FORCEPROP 1 LAST BODY_TYPE PLUMBING
J 2
(-1475 2625);
DISPLAY 0.872340 (-1475 2625);
PAINT GREEN (-1475 2625);
DISPLAY INVISIBLE (-1475 2625);
FORCEPROP 2 LAST CDS_LIB standard
J 0
(-1475 2575);
PAINT MONO (-1475 2575);
DISPLAY INVISIBLE (-1475 2575);
FORCEPROP 1 LAST PATH I27
J 2
(-1473 2575);
DISPLAY 0.872340 (-1473 2575);
PAINT GREEN (-1473 2575);
DISPLAY INVISIBLE (-1473 2575);
FORCEADD TAP..1
R 2
(-1475 2675);
FORCEPROP 3 LASTPIN (-1425 2675) SIG_NAME DMI_CPU0_PCH_TX_C_DN<6>
J 0
(-1415 2685);
DISPLAY 0.659574 (-1415 2685);
PAINT MONO (-1415 2685);
DISPLAY INVISIBLE (-1415 2685);
FORCEPROP 1 LASTPIN (-1425 2675) BN 6
J 2
(-1413 2683);
DISPLAY 0.680851 (-1413 2683);
PAINT GREEN (-1413 2683);
FORCEPROP 1 LAST HDL_TAP TRUE
J 2
(-1800 2550);
DISPLAY 0.872340 (-1800 2550);
PAINT GREEN (-1800 2550);
DISPLAY INVISIBLE (-1800 2550);
FORCEPROP 1 LAST BODY_TYPE PLUMBING
J 2
(-1475 2725);
DISPLAY 0.872340 (-1475 2725);
PAINT GREEN (-1475 2725);
DISPLAY INVISIBLE (-1475 2725);
FORCEPROP 2 LAST CDS_LIB standard
J 0
(-1475 2675);
PAINT MONO (-1475 2675);
DISPLAY INVISIBLE (-1475 2675);
FORCEPROP 1 LAST PATH I28
J 2
(-1473 2675);
DISPLAY 0.872340 (-1473 2675);
PAINT GREEN (-1473 2675);
DISPLAY INVISIBLE (-1473 2675);
FORCEADD OFFPAGE..1
(-2675 3350);
FORCEPROP 2 LAST $XR0 178 
J 0
(-2957 3350);
DISPLAY 0.638298 (-2957 3350);
PAINT MONO (-2957 3350);
FORCEPROP 1 LAST COMMENT_BODY TRUE
J 0
(-2550 3250);
DISPLAY 0.872340 (-2550 3250);
PAINT GREEN (-2550 3250);
DISPLAY INVISIBLE (-2550 3250);
FORCEPROP 1 LAST OFFPAGE TRUE
J 0
(-2350 3225);
DISPLAY 0.872340 (-2350 3225);
PAINT GREEN (-2350 3225);
DISPLAY INVISIBLE (-2350 3225);
FORCEPROP 2 LAST CDS_LIB standard
J 0
(-2675 3350);
DISPLAY INVISIBLE (-2675 3350);
FORCEPROP 2 LAST PATH I29
J 0
(-2950 3400);
DISPLAY 1.021277 (-2950 3400);
DISPLAY INVISIBLE (-2950 3400);
FORCEADD OFFPAGE..1
(-2450 1025);
FORCEPROP 2 LAST $XR0 190 
J 0
(-2732 1025);
DISPLAY 0.638298 (-2732 1025);
PAINT MONO (-2732 1025);
FORCEPROP 2 LAST CDS_LIB standard
J 0
(-2450 1025);
PAINT MONO (-2450 1025);
DISPLAY INVISIBLE (-2450 1025);
FORCEPROP 1 LAST OFFPAGE TRUE
J 0
(-2125 900);
DISPLAY 0.872340 (-2125 900);
DISPLAY INVISIBLE (-2125 900);
FORCEPROP 1 LAST COMMENT_BODY TRUE
J 0
(-2325 925);
DISPLAY 0.872340 (-2325 925);
PAINT GREEN (-2325 925);
DISPLAY INVISIBLE (-2325 925);
FORCEPROP 2 LAST PATH I3
J 0
(-2725 1075);
DISPLAY 1.021277 (-2725 1075);
DISPLAY INVISIBLE (-2725 1075);
FORCEADD OFFPAGE..1
(-2675 3300);
FORCEPROP 2 LAST $XR0 178 
J 0
(-2957 3300);
DISPLAY 0.638298 (-2957 3300);
PAINT MONO (-2957 3300);
FORCEPROP 1 LAST COMMENT_BODY TRUE
J 0
(-2550 3200);
DISPLAY 0.872340 (-2550 3200);
PAINT GREEN (-2550 3200);
DISPLAY INVISIBLE (-2550 3200);
FORCEPROP 1 LAST OFFPAGE TRUE
J 0
(-2350 3175);
DISPLAY 0.872340 (-2350 3175);
PAINT GREEN (-2350 3175);
DISPLAY INVISIBLE (-2350 3175);
FORCEPROP 2 LAST CDS_LIB standard
J 0
(-2675 3300);
DISPLAY INVISIBLE (-2675 3300);
FORCEPROP 2 LAST PATH I30
J 0
(-2950 3350);
DISPLAY 1.021277 (-2950 3350);
DISPLAY INVISIBLE (-2950 3350);
FORCEADD TAP..1
R 2
(-1625 2725);
FORCEPROP 3 LASTPIN (-1575 2725) SIG_NAME DMI_CPU0_PCH_TX_C_DP<6>
J 0
(-1565 2735);
DISPLAY 0.659574 (-1565 2735);
PAINT MONO (-1565 2735);
DISPLAY INVISIBLE (-1565 2735);
FORCEPROP 1 LASTPIN (-1575 2725) BN 6
J 2
(-1563 2733);
DISPLAY 0.680851 (-1563 2733);
PAINT GREEN (-1563 2733);
FORCEPROP 1 LAST HDL_TAP TRUE
J 2
(-1950 2600);
DISPLAY 0.872340 (-1950 2600);
PAINT GREEN (-1950 2600);
DISPLAY INVISIBLE (-1950 2600);
FORCEPROP 1 LAST BODY_TYPE PLUMBING
J 2
(-1625 2775);
DISPLAY 0.872340 (-1625 2775);
PAINT GREEN (-1625 2775);
DISPLAY INVISIBLE (-1625 2775);
FORCEPROP 2 LAST CDS_LIB standard
J 0
(-1625 2725);
PAINT MONO (-1625 2725);
DISPLAY INVISIBLE (-1625 2725);
FORCEPROP 1 LAST PATH I31
J 2
(-1623 2725);
DISPLAY 0.872340 (-1623 2725);
PAINT GREEN (-1623 2725);
DISPLAY INVISIBLE (-1623 2725);
FORCEADD TAP..1
R 2
(-1625 2825);
FORCEPROP 3 LASTPIN (-1575 2825) SIG_NAME DMI_CPU0_PCH_TX_C_DP<5>
J 0
(-1565 2835);
DISPLAY 0.659574 (-1565 2835);
PAINT MONO (-1565 2835);
DISPLAY INVISIBLE (-1565 2835);
FORCEPROP 1 LASTPIN (-1575 2825) BN 5
J 2
(-1563 2833);
DISPLAY 0.680851 (-1563 2833);
PAINT GREEN (-1563 2833);
FORCEPROP 1 LAST HDL_TAP TRUE
J 2
(-1950 2700);
DISPLAY 0.872340 (-1950 2700);
PAINT GREEN (-1950 2700);
DISPLAY INVISIBLE (-1950 2700);
FORCEPROP 1 LAST BODY_TYPE PLUMBING
J 2
(-1625 2875);
DISPLAY 0.872340 (-1625 2875);
PAINT GREEN (-1625 2875);
DISPLAY INVISIBLE (-1625 2875);
FORCEPROP 2 LAST CDS_LIB standard
J 0
(-1625 2825);
PAINT MONO (-1625 2825);
DISPLAY INVISIBLE (-1625 2825);
FORCEPROP 1 LAST PATH I32
J 2
(-1623 2825);
DISPLAY 0.872340 (-1623 2825);
PAINT GREEN (-1623 2825);
DISPLAY INVISIBLE (-1623 2825);
FORCEADD TAP..1
R 2
(-1625 2925);
FORCEPROP 3 LASTPIN (-1575 2925) SIG_NAME DMI_CPU0_PCH_TX_C_DP<4>
J 0
(-1565 2935);
DISPLAY 0.659574 (-1565 2935);
PAINT MONO (-1565 2935);
DISPLAY INVISIBLE (-1565 2935);
FORCEPROP 1 LASTPIN (-1575 2925) BN 4
J 2
(-1563 2933);
DISPLAY 0.680851 (-1563 2933);
PAINT GREEN (-1563 2933);
FORCEPROP 1 LAST HDL_TAP TRUE
J 2
(-1950 2800);
DISPLAY 0.872340 (-1950 2800);
PAINT GREEN (-1950 2800);
DISPLAY INVISIBLE (-1950 2800);
FORCEPROP 1 LAST BODY_TYPE PLUMBING
J 2
(-1625 2975);
DISPLAY 0.872340 (-1625 2975);
PAINT GREEN (-1625 2975);
DISPLAY INVISIBLE (-1625 2975);
FORCEPROP 2 LAST CDS_LIB standard
J 0
(-1625 2925);
PAINT MONO (-1625 2925);
DISPLAY INVISIBLE (-1625 2925);
FORCEPROP 1 LAST PATH I33
J 2
(-1623 2925);
DISPLAY 0.872340 (-1623 2925);
PAINT GREEN (-1623 2925);
DISPLAY INVISIBLE (-1623 2925);
FORCEADD TAP..1
R 2
(-1475 2775);
FORCEPROP 3 LASTPIN (-1425 2775) SIG_NAME DMI_CPU0_PCH_TX_C_DN<5>
J 0
(-1415 2785);
DISPLAY 0.659574 (-1415 2785);
PAINT MONO (-1415 2785);
DISPLAY INVISIBLE (-1415 2785);
FORCEPROP 1 LASTPIN (-1425 2775) BN 5
J 2
(-1413 2783);
DISPLAY 0.680851 (-1413 2783);
PAINT GREEN (-1413 2783);
FORCEPROP 1 LAST HDL_TAP TRUE
J 2
(-1800 2650);
DISPLAY 0.872340 (-1800 2650);
PAINT GREEN (-1800 2650);
DISPLAY INVISIBLE (-1800 2650);
FORCEPROP 1 LAST BODY_TYPE PLUMBING
J 2
(-1475 2825);
DISPLAY 0.872340 (-1475 2825);
PAINT GREEN (-1475 2825);
DISPLAY INVISIBLE (-1475 2825);
FORCEPROP 2 LAST CDS_LIB standard
J 0
(-1475 2775);
PAINT MONO (-1475 2775);
DISPLAY INVISIBLE (-1475 2775);
FORCEPROP 1 LAST PATH I34
J 2
(-1473 2775);
DISPLAY 0.872340 (-1473 2775);
PAINT GREEN (-1473 2775);
DISPLAY INVISIBLE (-1473 2775);
FORCEADD TAP..1
R 2
(-1475 2875);
FORCEPROP 3 LASTPIN (-1425 2875) SIG_NAME DMI_CPU0_PCH_TX_C_DN<4>
J 0
(-1415 2885);
DISPLAY 0.659574 (-1415 2885);
PAINT MONO (-1415 2885);
DISPLAY INVISIBLE (-1415 2885);
FORCEPROP 1 LASTPIN (-1425 2875) BN 4
J 2
(-1413 2883);
DISPLAY 0.680851 (-1413 2883);
PAINT GREEN (-1413 2883);
FORCEPROP 1 LAST HDL_TAP TRUE
J 2
(-1800 2750);
DISPLAY 0.872340 (-1800 2750);
PAINT GREEN (-1800 2750);
DISPLAY INVISIBLE (-1800 2750);
FORCEPROP 1 LAST BODY_TYPE PLUMBING
J 2
(-1475 2925);
DISPLAY 0.872340 (-1475 2925);
PAINT GREEN (-1475 2925);
DISPLAY INVISIBLE (-1475 2925);
FORCEPROP 2 LAST CDS_LIB standard
J 0
(-1475 2875);
PAINT MONO (-1475 2875);
DISPLAY INVISIBLE (-1475 2875);
FORCEPROP 1 LAST PATH I35
J 2
(-1473 2875);
DISPLAY 0.872340 (-1473 2875);
PAINT GREEN (-1473 2875);
DISPLAY INVISIBLE (-1473 2875);
FORCEADD TAP..1
R 2
(-1625 3025);
FORCEPROP 3 LASTPIN (-1575 3025) SIG_NAME DMI_CPU0_PCH_TX_C_DP<3>
J 0
(-1565 3035);
DISPLAY 0.659574 (-1565 3035);
PAINT MONO (-1565 3035);
DISPLAY INVISIBLE (-1565 3035);
FORCEPROP 1 LASTPIN (-1575 3025) BN 3
J 2
(-1563 3033);
DISPLAY 0.680851 (-1563 3033);
PAINT GREEN (-1563 3033);
FORCEPROP 1 LAST HDL_TAP TRUE
J 2
(-1950 2900);
DISPLAY 0.872340 (-1950 2900);
PAINT GREEN (-1950 2900);
DISPLAY INVISIBLE (-1950 2900);
FORCEPROP 1 LAST BODY_TYPE PLUMBING
J 2
(-1625 3075);
DISPLAY 0.872340 (-1625 3075);
PAINT GREEN (-1625 3075);
DISPLAY INVISIBLE (-1625 3075);
FORCEPROP 2 LAST CDS_LIB standard
J 0
(-1625 3025);
PAINT MONO (-1625 3025);
DISPLAY INVISIBLE (-1625 3025);
FORCEPROP 1 LAST PATH I36
J 2
(-1623 3025);
DISPLAY 0.872340 (-1623 3025);
PAINT GREEN (-1623 3025);
DISPLAY INVISIBLE (-1623 3025);
FORCEADD TAP..1
R 2
(-1625 3225);
FORCEPROP 3 LASTPIN (-1575 3225) SIG_NAME DMI_CPU0_PCH_TX_C_DP<1>
J 0
(-1565 3235);
DISPLAY 0.659574 (-1565 3235);
PAINT MONO (-1565 3235);
DISPLAY INVISIBLE (-1565 3235);
FORCEPROP 1 LASTPIN (-1575 3225) BN 1
J 2
(-1563 3233);
DISPLAY 0.680851 (-1563 3233);
PAINT GREEN (-1563 3233);
FORCEPROP 1 LAST HDL_TAP TRUE
J 2
(-1950 3100);
DISPLAY 0.872340 (-1950 3100);
PAINT GREEN (-1950 3100);
DISPLAY INVISIBLE (-1950 3100);
FORCEPROP 1 LAST BODY_TYPE PLUMBING
J 2
(-1625 3275);
DISPLAY 0.872340 (-1625 3275);
PAINT GREEN (-1625 3275);
DISPLAY INVISIBLE (-1625 3275);
FORCEPROP 2 LAST CDS_LIB standard
J 0
(-1625 3225);
PAINT MONO (-1625 3225);
DISPLAY INVISIBLE (-1625 3225);
FORCEPROP 1 LAST PATH I37
J 2
(-1623 3225);
DISPLAY 0.872340 (-1623 3225);
PAINT GREEN (-1623 3225);
DISPLAY INVISIBLE (-1623 3225);
FORCEADD TAP..1
R 2
(-1625 3125);
FORCEPROP 3 LASTPIN (-1575 3125) SIG_NAME DMI_CPU0_PCH_TX_C_DP<2>
J 0
(-1565 3135);
DISPLAY 0.659574 (-1565 3135);
PAINT MONO (-1565 3135);
DISPLAY INVISIBLE (-1565 3135);
FORCEPROP 1 LASTPIN (-1575 3125) BN 2
J 2
(-1563 3133);
DISPLAY 0.680851 (-1563 3133);
PAINT GREEN (-1563 3133);
FORCEPROP 1 LAST HDL_TAP TRUE
J 2
(-1950 3000);
DISPLAY 0.872340 (-1950 3000);
PAINT GREEN (-1950 3000);
DISPLAY INVISIBLE (-1950 3000);
FORCEPROP 1 LAST BODY_TYPE PLUMBING
J 2
(-1625 3175);
DISPLAY 0.872340 (-1625 3175);
PAINT GREEN (-1625 3175);
DISPLAY INVISIBLE (-1625 3175);
FORCEPROP 2 LAST CDS_LIB standard
J 0
(-1625 3125);
PAINT MONO (-1625 3125);
DISPLAY INVISIBLE (-1625 3125);
FORCEPROP 1 LAST PATH I38
J 2
(-1623 3125);
DISPLAY 0.872340 (-1623 3125);
PAINT GREEN (-1623 3125);
DISPLAY INVISIBLE (-1623 3125);
FORCEADD TAP..1
R 2
(-1475 3075);
FORCEPROP 3 LASTPIN (-1425 3075) SIG_NAME DMI_CPU0_PCH_TX_C_DN<2>
J 0
(-1415 3085);
DISPLAY 0.659574 (-1415 3085);
PAINT MONO (-1415 3085);
DISPLAY INVISIBLE (-1415 3085);
FORCEPROP 1 LASTPIN (-1425 3075) BN 2
J 2
(-1413 3083);
DISPLAY 0.680851 (-1413 3083);
PAINT GREEN (-1413 3083);
FORCEPROP 1 LAST HDL_TAP TRUE
J 2
(-1800 2950);
DISPLAY 0.872340 (-1800 2950);
PAINT GREEN (-1800 2950);
DISPLAY INVISIBLE (-1800 2950);
FORCEPROP 1 LAST BODY_TYPE PLUMBING
J 2
(-1475 3125);
DISPLAY 0.872340 (-1475 3125);
PAINT GREEN (-1475 3125);
DISPLAY INVISIBLE (-1475 3125);
FORCEPROP 2 LAST CDS_LIB standard
J 0
(-1475 3075);
PAINT MONO (-1475 3075);
DISPLAY INVISIBLE (-1475 3075);
FORCEPROP 1 LAST PATH I39
J 2
(-1473 3075);
DISPLAY 0.872340 (-1473 3075);
PAINT GREEN (-1473 3075);
DISPLAY INVISIBLE (-1473 3075);
FORCEADD OFFPAGE..1
(-2450 975);
FORCEPROP 2 LAST $XR0 190 
J 0
(-2732 975);
DISPLAY 0.638298 (-2732 975);
PAINT MONO (-2732 975);
FORCEPROP 2 LAST CDS_LIB standard
J 0
(-2450 975);
PAINT MONO (-2450 975);
DISPLAY INVISIBLE (-2450 975);
FORCEPROP 1 LAST OFFPAGE TRUE
J 0
(-2125 850);
DISPLAY 0.872340 (-2125 850);
DISPLAY INVISIBLE (-2125 850);
FORCEPROP 1 LAST COMMENT_BODY TRUE
J 0
(-2325 875);
DISPLAY 0.872340 (-2325 875);
PAINT GREEN (-2325 875);
DISPLAY INVISIBLE (-2325 875);
FORCEPROP 2 LAST PATH I4
J 0
(-2725 1025);
DISPLAY 1.021277 (-2725 1025);
DISPLAY INVISIBLE (-2725 1025);
FORCEADD TAP..1
R 2
(-1475 2975);
FORCEPROP 3 LASTPIN (-1425 2975) SIG_NAME DMI_CPU0_PCH_TX_C_DN<3>
J 0
(-1415 2985);
DISPLAY 0.659574 (-1415 2985);
PAINT MONO (-1415 2985);
DISPLAY INVISIBLE (-1415 2985);
FORCEPROP 1 LASTPIN (-1425 2975) BN 3
J 2
(-1413 2983);
DISPLAY 0.680851 (-1413 2983);
PAINT GREEN (-1413 2983);
FORCEPROP 1 LAST HDL_TAP TRUE
J 2
(-1800 2850);
DISPLAY 0.872340 (-1800 2850);
PAINT GREEN (-1800 2850);
DISPLAY INVISIBLE (-1800 2850);
FORCEPROP 1 LAST BODY_TYPE PLUMBING
J 2
(-1475 3025);
DISPLAY 0.872340 (-1475 3025);
PAINT GREEN (-1475 3025);
DISPLAY INVISIBLE (-1475 3025);
FORCEPROP 2 LAST CDS_LIB standard
J 0
(-1475 2975);
PAINT MONO (-1475 2975);
DISPLAY INVISIBLE (-1475 2975);
FORCEPROP 1 LAST PATH I40
J 2
(-1473 2975);
DISPLAY 0.872340 (-1473 2975);
PAINT GREEN (-1473 2975);
DISPLAY INVISIBLE (-1473 2975);
FORCEADD TAP..1
R 2
(-1475 3175);
FORCEPROP 3 LASTPIN (-1425 3175) SIG_NAME DMI_CPU0_PCH_TX_C_DN<1>
J 0
(-1415 3185);
DISPLAY 0.659574 (-1415 3185);
PAINT MONO (-1415 3185);
DISPLAY INVISIBLE (-1415 3185);
FORCEPROP 1 LASTPIN (-1425 3175) BN 1
J 2
(-1413 3183);
DISPLAY 0.680851 (-1413 3183);
PAINT GREEN (-1413 3183);
FORCEPROP 1 LAST HDL_TAP TRUE
J 2
(-1800 3050);
DISPLAY 0.872340 (-1800 3050);
PAINT GREEN (-1800 3050);
DISPLAY INVISIBLE (-1800 3050);
FORCEPROP 1 LAST BODY_TYPE PLUMBING
J 2
(-1475 3225);
DISPLAY 0.872340 (-1475 3225);
PAINT GREEN (-1475 3225);
DISPLAY INVISIBLE (-1475 3225);
FORCEPROP 2 LAST CDS_LIB standard
J 0
(-1475 3175);
PAINT MONO (-1475 3175);
DISPLAY INVISIBLE (-1475 3175);
FORCEPROP 1 LAST PATH I41
J 2
(-1473 3175);
DISPLAY 0.872340 (-1473 3175);
PAINT GREEN (-1473 3175);
DISPLAY INVISIBLE (-1473 3175);
FORCEADD TAP..1
R 2
(-1625 3325);
FORCEPROP 3 LASTPIN (-1575 3325) SIG_NAME DMI_CPU0_PCH_TX_C_DP<0>
J 0
(-1565 3335);
DISPLAY 0.659574 (-1565 3335);
PAINT MONO (-1565 3335);
DISPLAY INVISIBLE (-1565 3335);
FORCEPROP 1 LASTPIN (-1575 3325) BN 0
J 2
(-1563 3333);
DISPLAY 0.680851 (-1563 3333);
PAINT GREEN (-1563 3333);
FORCEPROP 1 LAST HDL_TAP TRUE
J 2
(-1950 3200);
DISPLAY 0.872340 (-1950 3200);
PAINT GREEN (-1950 3200);
DISPLAY INVISIBLE (-1950 3200);
FORCEPROP 1 LAST BODY_TYPE PLUMBING
J 2
(-1625 3375);
DISPLAY 0.872340 (-1625 3375);
PAINT GREEN (-1625 3375);
DISPLAY INVISIBLE (-1625 3375);
FORCEPROP 2 LAST CDS_LIB standard
J 0
(-1625 3325);
PAINT MONO (-1625 3325);
DISPLAY INVISIBLE (-1625 3325);
FORCEPROP 1 LAST PATH I42
J 2
(-1623 3325);
DISPLAY 0.872340 (-1623 3325);
PAINT GREEN (-1623 3325);
DISPLAY INVISIBLE (-1623 3325);
FORCEADD TAP..1
R 2
(-1475 3275);
FORCEPROP 3 LASTPIN (-1425 3275) SIG_NAME DMI_CPU0_PCH_TX_C_DN<0>
J 0
(-1415 3285);
DISPLAY 0.659574 (-1415 3285);
PAINT MONO (-1415 3285);
DISPLAY INVISIBLE (-1415 3285);
FORCEPROP 1 LASTPIN (-1425 3275) BN 0
J 2
(-1413 3283);
DISPLAY 0.680851 (-1413 3283);
PAINT GREEN (-1413 3283);
FORCEPROP 1 LAST HDL_TAP TRUE
J 2
(-1800 3150);
DISPLAY 0.872340 (-1800 3150);
PAINT GREEN (-1800 3150);
DISPLAY INVISIBLE (-1800 3150);
FORCEPROP 1 LAST BODY_TYPE PLUMBING
J 2
(-1475 3325);
DISPLAY 0.872340 (-1475 3325);
PAINT GREEN (-1475 3325);
DISPLAY INVISIBLE (-1475 3325);
FORCEPROP 2 LAST CDS_LIB standard
J 0
(-1475 3275);
PAINT MONO (-1475 3275);
DISPLAY INVISIBLE (-1475 3275);
FORCEPROP 1 LAST PATH I43
J 2
(-1473 3275);
DISPLAY 0.872340 (-1473 3275);
PAINT GREEN (-1473 3275);
DISPLAY INVISIBLE (-1473 3275);
FORCEADD TAP..1
(2325 2575);
FORCEPROP 3 LASTPIN (2275 2575) SIG_NAME DMI_CPU0_PCH_RX_DN<7>
J 0
(2285 2585);
DISPLAY 0.659574 (2285 2585);
PAINT MONO (2285 2585);
DISPLAY INVISIBLE (2285 2585);
FORCEPROP 1 LASTPIN (2275 2575) BN 7
J 0
(2263 2583);
DISPLAY 0.680851 (2263 2583);
PAINT GREEN (2263 2583);
FORCEPROP 1 LAST HDL_TAP TRUE
J 0
(2650 2450);
DISPLAY 0.872340 (2650 2450);
PAINT GREEN (2650 2450);
DISPLAY INVISIBLE (2650 2450);
FORCEPROP 1 LAST BODY_TYPE PLUMBING
J 0
(2325 2625);
DISPLAY 0.872340 (2325 2625);
PAINT GREEN (2325 2625);
DISPLAY INVISIBLE (2325 2625);
FORCEPROP 2 LAST CDS_LIB standard
J 0
(2325 2575);
DISPLAY INVISIBLE (2325 2575);
FORCEPROP 1 LAST PATH I44
J 0
(2323 2575);
DISPLAY 0.872340 (2323 2575);
PAINT GREEN (2323 2575);
DISPLAY INVISIBLE (2323 2575);
FORCEADD TAP..1
(2325 2675);
FORCEPROP 3 LASTPIN (2275 2675) SIG_NAME DMI_CPU0_PCH_RX_DN<6>
J 0
(2285 2685);
DISPLAY 0.659574 (2285 2685);
PAINT MONO (2285 2685);
DISPLAY INVISIBLE (2285 2685);
FORCEPROP 1 LASTPIN (2275 2675) BN 6
J 0
(2263 2683);
DISPLAY 0.680851 (2263 2683);
PAINT GREEN (2263 2683);
FORCEPROP 1 LAST HDL_TAP TRUE
J 0
(2650 2550);
DISPLAY 0.872340 (2650 2550);
PAINT GREEN (2650 2550);
DISPLAY INVISIBLE (2650 2550);
FORCEPROP 1 LAST BODY_TYPE PLUMBING
J 0
(2325 2725);
DISPLAY 0.872340 (2325 2725);
PAINT GREEN (2325 2725);
DISPLAY INVISIBLE (2325 2725);
FORCEPROP 2 LAST CDS_LIB standard
J 0
(2325 2675);
DISPLAY INVISIBLE (2325 2675);
FORCEPROP 1 LAST PATH I45
J 0
(2323 2675);
DISPLAY 0.872340 (2323 2675);
PAINT GREEN (2323 2675);
DISPLAY INVISIBLE (2323 2675);
FORCEADD TAP..1
(2475 2625);
FORCEPROP 3 LASTPIN (2425 2625) SIG_NAME DMI_CPU0_PCH_RX_DP<7>
J 0
(2435 2635);
DISPLAY 0.659574 (2435 2635);
PAINT MONO (2435 2635);
DISPLAY INVISIBLE (2435 2635);
FORCEPROP 1 LASTPIN (2425 2625) BN 7
J 0
(2413 2633);
DISPLAY 0.680851 (2413 2633);
PAINT GREEN (2413 2633);
FORCEPROP 1 LAST HDL_TAP TRUE
J 0
(2800 2500);
DISPLAY 0.872340 (2800 2500);
PAINT GREEN (2800 2500);
DISPLAY INVISIBLE (2800 2500);
FORCEPROP 1 LAST BODY_TYPE PLUMBING
J 0
(2475 2675);
DISPLAY 0.872340 (2475 2675);
PAINT GREEN (2475 2675);
DISPLAY INVISIBLE (2475 2675);
FORCEPROP 2 LAST CDS_LIB standard
J 0
(2475 2625);
DISPLAY INVISIBLE (2475 2625);
FORCEPROP 1 LAST PATH I46
J 0
(2473 2625);
DISPLAY 0.872340 (2473 2625);
PAINT GREEN (2473 2625);
DISPLAY INVISIBLE (2473 2625);
FORCEADD TAP..1
(2325 2775);
FORCEPROP 3 LASTPIN (2275 2775) SIG_NAME DMI_CPU0_PCH_RX_DN<5>
J 0
(2285 2785);
DISPLAY 0.659574 (2285 2785);
PAINT MONO (2285 2785);
DISPLAY INVISIBLE (2285 2785);
FORCEPROP 1 LASTPIN (2275 2775) BN 5
J 0
(2263 2783);
DISPLAY 0.680851 (2263 2783);
PAINT GREEN (2263 2783);
FORCEPROP 1 LAST HDL_TAP TRUE
J 0
(2650 2650);
DISPLAY 0.872340 (2650 2650);
PAINT GREEN (2650 2650);
DISPLAY INVISIBLE (2650 2650);
FORCEPROP 1 LAST BODY_TYPE PLUMBING
J 0
(2325 2825);
DISPLAY 0.872340 (2325 2825);
PAINT GREEN (2325 2825);
DISPLAY INVISIBLE (2325 2825);
FORCEPROP 2 LAST CDS_LIB standard
J 0
(2325 2775);
DISPLAY INVISIBLE (2325 2775);
FORCEPROP 1 LAST PATH I47
J 0
(2323 2775);
DISPLAY 0.872340 (2323 2775);
PAINT GREEN (2323 2775);
DISPLAY INVISIBLE (2323 2775);
FORCEADD TAP..1
(2325 2875);
FORCEPROP 3 LASTPIN (2275 2875) SIG_NAME DMI_CPU0_PCH_RX_DN<4>
J 0
(2285 2885);
DISPLAY 0.659574 (2285 2885);
PAINT MONO (2285 2885);
DISPLAY INVISIBLE (2285 2885);
FORCEPROP 1 LASTPIN (2275 2875) BN 4
J 0
(2263 2883);
DISPLAY 0.680851 (2263 2883);
PAINT GREEN (2263 2883);
FORCEPROP 1 LAST HDL_TAP TRUE
J 0
(2650 2750);
DISPLAY 0.872340 (2650 2750);
PAINT GREEN (2650 2750);
DISPLAY INVISIBLE (2650 2750);
FORCEPROP 1 LAST BODY_TYPE PLUMBING
J 0
(2325 2925);
DISPLAY 0.872340 (2325 2925);
PAINT GREEN (2325 2925);
DISPLAY INVISIBLE (2325 2925);
FORCEPROP 2 LAST CDS_LIB standard
J 0
(2325 2875);
DISPLAY INVISIBLE (2325 2875);
FORCEPROP 1 LAST PATH I48
J 0
(2323 2875);
DISPLAY 0.872340 (2323 2875);
PAINT GREEN (2323 2875);
DISPLAY INVISIBLE (2323 2875);
FORCEADD TAP..1
(2325 2975);
FORCEPROP 3 LASTPIN (2275 2975) SIG_NAME DMI_CPU0_PCH_RX_DN<3>
J 0
(2285 2985);
DISPLAY 0.659574 (2285 2985);
PAINT MONO (2285 2985);
DISPLAY INVISIBLE (2285 2985);
FORCEPROP 1 LASTPIN (2275 2975) BN 3
J 0
(2263 2983);
DISPLAY 0.680851 (2263 2983);
PAINT GREEN (2263 2983);
FORCEPROP 1 LAST HDL_TAP TRUE
J 0
(2650 2850);
DISPLAY 0.872340 (2650 2850);
PAINT GREEN (2650 2850);
DISPLAY INVISIBLE (2650 2850);
FORCEPROP 1 LAST BODY_TYPE PLUMBING
J 0
(2325 3025);
DISPLAY 0.872340 (2325 3025);
PAINT GREEN (2325 3025);
DISPLAY INVISIBLE (2325 3025);
FORCEPROP 2 LAST CDS_LIB standard
J 0
(2325 2975);
DISPLAY INVISIBLE (2325 2975);
FORCEPROP 1 LAST PATH I49
J 0
(2323 2975);
DISPLAY 0.872340 (2323 2975);
PAINT GREEN (2323 2975);
DISPLAY INVISIBLE (2323 2975);
FORCEADD OFFPAGE..1
(-2450 1075);
FORCEPROP 2 LAST $XR0 190 
J 0
(-2732 1075);
DISPLAY 0.638298 (-2732 1075);
PAINT MONO (-2732 1075);
FORCEPROP 2 LAST CDS_LIB standard
J 0
(-2450 1075);
PAINT MONO (-2450 1075);
DISPLAY INVISIBLE (-2450 1075);
FORCEPROP 1 LAST OFFPAGE TRUE
J 0
(-2125 950);
DISPLAY 0.872340 (-2125 950);
DISPLAY INVISIBLE (-2125 950);
FORCEPROP 1 LAST COMMENT_BODY TRUE
J 0
(-2325 975);
DISPLAY 0.872340 (-2325 975);
PAINT GREEN (-2325 975);
DISPLAY INVISIBLE (-2325 975);
FORCEPROP 2 LAST PATH I5
J 0
(-2725 1125);
DISPLAY 1.021277 (-2725 1125);
DISPLAY INVISIBLE (-2725 1125);
FORCEADD TAP..1
(2325 3075);
FORCEPROP 3 LASTPIN (2275 3075) SIG_NAME DMI_CPU0_PCH_RX_DN<2>
J 0
(2285 3085);
DISPLAY 0.659574 (2285 3085);
PAINT MONO (2285 3085);
DISPLAY INVISIBLE (2285 3085);
FORCEPROP 1 LASTPIN (2275 3075) BN 2
J 0
(2263 3083);
DISPLAY 0.680851 (2263 3083);
PAINT GREEN (2263 3083);
FORCEPROP 1 LAST HDL_TAP TRUE
J 0
(2650 2950);
DISPLAY 0.872340 (2650 2950);
PAINT GREEN (2650 2950);
DISPLAY INVISIBLE (2650 2950);
FORCEPROP 1 LAST BODY_TYPE PLUMBING
J 0
(2325 3125);
DISPLAY 0.872340 (2325 3125);
PAINT GREEN (2325 3125);
DISPLAY INVISIBLE (2325 3125);
FORCEPROP 2 LAST CDS_LIB standard
J 0
(2325 3075);
DISPLAY INVISIBLE (2325 3075);
FORCEPROP 1 LAST PATH I50
J 0
(2323 3075);
DISPLAY 0.872340 (2323 3075);
PAINT GREEN (2323 3075);
DISPLAY INVISIBLE (2323 3075);
FORCEADD TAP..1
(2325 3175);
FORCEPROP 3 LASTPIN (2275 3175) SIG_NAME DMI_CPU0_PCH_RX_DN<1>
J 0
(2285 3185);
DISPLAY 0.659574 (2285 3185);
PAINT MONO (2285 3185);
DISPLAY INVISIBLE (2285 3185);
FORCEPROP 1 LASTPIN (2275 3175) BN 1
J 0
(2263 3183);
DISPLAY 0.680851 (2263 3183);
PAINT GREEN (2263 3183);
FORCEPROP 1 LAST HDL_TAP TRUE
J 0
(2650 3050);
DISPLAY 0.872340 (2650 3050);
PAINT GREEN (2650 3050);
DISPLAY INVISIBLE (2650 3050);
FORCEPROP 1 LAST BODY_TYPE PLUMBING
J 0
(2325 3225);
DISPLAY 0.872340 (2325 3225);
PAINT GREEN (2325 3225);
DISPLAY INVISIBLE (2325 3225);
FORCEPROP 2 LAST CDS_LIB standard
J 0
(2325 3175);
DISPLAY INVISIBLE (2325 3175);
FORCEPROP 1 LAST PATH I51
J 0
(2323 3175);
DISPLAY 0.872340 (2323 3175);
PAINT GREEN (2323 3175);
DISPLAY INVISIBLE (2323 3175);
FORCEADD TAP..1
(2475 2725);
FORCEPROP 3 LASTPIN (2425 2725) SIG_NAME DMI_CPU0_PCH_RX_DP<6>
J 0
(2435 2735);
DISPLAY 0.659574 (2435 2735);
PAINT MONO (2435 2735);
DISPLAY INVISIBLE (2435 2735);
FORCEPROP 1 LASTPIN (2425 2725) BN 6
J 0
(2413 2733);
DISPLAY 0.680851 (2413 2733);
PAINT GREEN (2413 2733);
FORCEPROP 1 LAST HDL_TAP TRUE
J 0
(2800 2600);
DISPLAY 0.872340 (2800 2600);
PAINT GREEN (2800 2600);
DISPLAY INVISIBLE (2800 2600);
FORCEPROP 1 LAST BODY_TYPE PLUMBING
J 0
(2475 2775);
DISPLAY 0.872340 (2475 2775);
PAINT GREEN (2475 2775);
DISPLAY INVISIBLE (2475 2775);
FORCEPROP 2 LAST CDS_LIB standard
J 0
(2475 2725);
DISPLAY INVISIBLE (2475 2725);
FORCEPROP 1 LAST PATH I52
J 0
(2473 2725);
DISPLAY 0.872340 (2473 2725);
PAINT GREEN (2473 2725);
DISPLAY INVISIBLE (2473 2725);
FORCEADD TAP..1
(2475 2825);
FORCEPROP 3 LASTPIN (2425 2825) SIG_NAME DMI_CPU0_PCH_RX_DP<5>
J 0
(2435 2835);
DISPLAY 0.659574 (2435 2835);
PAINT MONO (2435 2835);
DISPLAY INVISIBLE (2435 2835);
FORCEPROP 1 LASTPIN (2425 2825) BN 5
J 0
(2413 2833);
DISPLAY 0.680851 (2413 2833);
PAINT GREEN (2413 2833);
FORCEPROP 1 LAST HDL_TAP TRUE
J 0
(2800 2700);
DISPLAY 0.872340 (2800 2700);
PAINT GREEN (2800 2700);
DISPLAY INVISIBLE (2800 2700);
FORCEPROP 1 LAST BODY_TYPE PLUMBING
J 0
(2475 2875);
DISPLAY 0.872340 (2475 2875);
PAINT GREEN (2475 2875);
DISPLAY INVISIBLE (2475 2875);
FORCEPROP 2 LAST CDS_LIB standard
J 0
(2475 2825);
DISPLAY INVISIBLE (2475 2825);
FORCEPROP 1 LAST PATH I53
J 0
(2473 2825);
DISPLAY 0.872340 (2473 2825);
PAINT GREEN (2473 2825);
DISPLAY INVISIBLE (2473 2825);
FORCEADD TAP..1
(2475 2925);
FORCEPROP 3 LASTPIN (2425 2925) SIG_NAME DMI_CPU0_PCH_RX_DP<4>
J 0
(2435 2935);
DISPLAY 0.659574 (2435 2935);
PAINT MONO (2435 2935);
DISPLAY INVISIBLE (2435 2935);
FORCEPROP 1 LASTPIN (2425 2925) BN 4
J 0
(2413 2933);
DISPLAY 0.680851 (2413 2933);
PAINT GREEN (2413 2933);
FORCEPROP 1 LAST HDL_TAP TRUE
J 0
(2800 2800);
DISPLAY 0.872340 (2800 2800);
PAINT GREEN (2800 2800);
DISPLAY INVISIBLE (2800 2800);
FORCEPROP 1 LAST BODY_TYPE PLUMBING
J 0
(2475 2975);
DISPLAY 0.872340 (2475 2975);
PAINT GREEN (2475 2975);
DISPLAY INVISIBLE (2475 2975);
FORCEPROP 2 LAST CDS_LIB standard
J 0
(2475 2925);
DISPLAY INVISIBLE (2475 2925);
FORCEPROP 1 LAST PATH I54
J 0
(2473 2925);
DISPLAY 0.872340 (2473 2925);
PAINT GREEN (2473 2925);
DISPLAY INVISIBLE (2473 2925);
FORCEADD TAP..1
(2475 3025);
FORCEPROP 3 LASTPIN (2425 3025) SIG_NAME DMI_CPU0_PCH_RX_DP<3>
J 0
(2435 3035);
DISPLAY 0.659574 (2435 3035);
PAINT MONO (2435 3035);
DISPLAY INVISIBLE (2435 3035);
FORCEPROP 1 LASTPIN (2425 3025) BN 3
J 0
(2413 3033);
DISPLAY 0.680851 (2413 3033);
PAINT GREEN (2413 3033);
FORCEPROP 1 LAST HDL_TAP TRUE
J 0
(2800 2900);
DISPLAY 0.872340 (2800 2900);
PAINT GREEN (2800 2900);
DISPLAY INVISIBLE (2800 2900);
FORCEPROP 1 LAST BODY_TYPE PLUMBING
J 0
(2475 3075);
DISPLAY 0.872340 (2475 3075);
PAINT GREEN (2475 3075);
DISPLAY INVISIBLE (2475 3075);
FORCEPROP 2 LAST CDS_LIB standard
J 0
(2475 3025);
DISPLAY INVISIBLE (2475 3025);
FORCEPROP 1 LAST PATH I55
J 0
(2473 3025);
DISPLAY 0.872340 (2473 3025);
PAINT GREEN (2473 3025);
DISPLAY INVISIBLE (2473 3025);
FORCEADD TAP..1
(2475 3125);
FORCEPROP 3 LASTPIN (2425 3125) SIG_NAME DMI_CPU0_PCH_RX_DP<2>
J 0
(2435 3135);
DISPLAY 0.659574 (2435 3135);
PAINT MONO (2435 3135);
DISPLAY INVISIBLE (2435 3135);
FORCEPROP 1 LASTPIN (2425 3125) BN 2
J 0
(2413 3133);
DISPLAY 0.680851 (2413 3133);
PAINT GREEN (2413 3133);
FORCEPROP 1 LAST HDL_TAP TRUE
J 0
(2800 3000);
DISPLAY 0.872340 (2800 3000);
PAINT GREEN (2800 3000);
DISPLAY INVISIBLE (2800 3000);
FORCEPROP 1 LAST BODY_TYPE PLUMBING
J 0
(2475 3175);
DISPLAY 0.872340 (2475 3175);
PAINT GREEN (2475 3175);
DISPLAY INVISIBLE (2475 3175);
FORCEPROP 2 LAST CDS_LIB standard
J 0
(2475 3125);
DISPLAY INVISIBLE (2475 3125);
FORCEPROP 1 LAST PATH I56
J 0
(2473 3125);
DISPLAY 0.872340 (2473 3125);
PAINT GREEN (2473 3125);
DISPLAY INVISIBLE (2473 3125);
FORCEADD TAP..1
(2475 3225);
FORCEPROP 3 LASTPIN (2425 3225) SIG_NAME DMI_CPU0_PCH_RX_DP<1>
J 0
(2435 3235);
DISPLAY 0.659574 (2435 3235);
PAINT MONO (2435 3235);
DISPLAY INVISIBLE (2435 3235);
FORCEPROP 1 LASTPIN (2425 3225) BN 1
J 0
(2413 3233);
DISPLAY 0.680851 (2413 3233);
PAINT GREEN (2413 3233);
FORCEPROP 1 LAST HDL_TAP TRUE
J 0
(2800 3100);
DISPLAY 0.872340 (2800 3100);
PAINT GREEN (2800 3100);
DISPLAY INVISIBLE (2800 3100);
FORCEPROP 1 LAST BODY_TYPE PLUMBING
J 0
(2475 3275);
DISPLAY 0.872340 (2475 3275);
PAINT GREEN (2475 3275);
DISPLAY INVISIBLE (2475 3275);
FORCEPROP 2 LAST CDS_LIB standard
J 0
(2475 3225);
DISPLAY INVISIBLE (2475 3225);
FORCEPROP 1 LAST PATH I57
J 0
(2473 3225);
DISPLAY 0.872340 (2473 3225);
PAINT GREEN (2473 3225);
DISPLAY INVISIBLE (2473 3225);
FORCEADD TAP..1
(2325 3275);
FORCEPROP 3 LASTPIN (2275 3275) SIG_NAME DMI_CPU0_PCH_RX_DN<0>
J 0
(2285 3285);
DISPLAY 0.659574 (2285 3285);
PAINT MONO (2285 3285);
DISPLAY INVISIBLE (2285 3285);
FORCEPROP 1 LASTPIN (2275 3275) BN 0
J 0
(2263 3283);
DISPLAY 0.680851 (2263 3283);
PAINT GREEN (2263 3283);
FORCEPROP 1 LAST HDL_TAP TRUE
J 0
(2650 3150);
DISPLAY 0.872340 (2650 3150);
PAINT GREEN (2650 3150);
DISPLAY INVISIBLE (2650 3150);
FORCEPROP 1 LAST BODY_TYPE PLUMBING
J 0
(2325 3325);
DISPLAY 0.872340 (2325 3325);
PAINT GREEN (2325 3325);
DISPLAY INVISIBLE (2325 3325);
FORCEPROP 2 LAST CDS_LIB standard
J 0
(2325 3275);
DISPLAY INVISIBLE (2325 3275);
FORCEPROP 1 LAST PATH I58
J 0
(2323 3275);
DISPLAY 0.872340 (2323 3275);
PAINT GREEN (2323 3275);
DISPLAY INVISIBLE (2323 3275);
FORCEADD TAP..1
(2475 3325);
FORCEPROP 3 LASTPIN (2425 3325) SIG_NAME DMI_CPU0_PCH_RX_DP<0>
J 0
(2435 3335);
DISPLAY 0.659574 (2435 3335);
PAINT MONO (2435 3335);
DISPLAY INVISIBLE (2435 3335);
FORCEPROP 1 LASTPIN (2425 3325) BN 0
J 0
(2413 3333);
DISPLAY 0.680851 (2413 3333);
PAINT GREEN (2413 3333);
FORCEPROP 1 LAST HDL_TAP TRUE
J 0
(2800 3200);
DISPLAY 0.872340 (2800 3200);
PAINT GREEN (2800 3200);
DISPLAY INVISIBLE (2800 3200);
FORCEPROP 1 LAST BODY_TYPE PLUMBING
J 0
(2475 3375);
DISPLAY 0.872340 (2475 3375);
PAINT GREEN (2475 3375);
DISPLAY INVISIBLE (2475 3375);
FORCEPROP 2 LAST CDS_LIB standard
J 0
(2475 3325);
DISPLAY INVISIBLE (2475 3325);
FORCEPROP 1 LAST PATH I59
J 0
(2473 3325);
DISPLAY 0.872340 (2473 3325);
PAINT GREEN (2473 3325);
DISPLAY INVISIBLE (2473 3325);
FORCEADD OFFPAGE..1
(-2450 1125);
FORCEPROP 2 LAST $XR0 190 
J 0
(-2732 1125);
DISPLAY 0.638298 (-2732 1125);
PAINT MONO (-2732 1125);
FORCEPROP 2 LAST CDS_LIB standard
J 0
(-2450 1125);
PAINT MONO (-2450 1125);
DISPLAY INVISIBLE (-2450 1125);
FORCEPROP 1 LAST OFFPAGE TRUE
J 0
(-2125 1000);
DISPLAY 0.872340 (-2125 1000);
DISPLAY INVISIBLE (-2125 1000);
FORCEPROP 1 LAST COMMENT_BODY TRUE
J 0
(-2325 1025);
DISPLAY 0.872340 (-2325 1025);
PAINT GREEN (-2325 1025);
DISPLAY INVISIBLE (-2325 1025);
FORCEPROP 2 LAST PATH I6
J 0
(-2725 1175);
DISPLAY 1.021277 (-2725 1175);
DISPLAY INVISIBLE (-2725 1175);
FORCEADD Q_CAP_DIFFBUS..2
(3025 925);
FORCEPROP 1 LAST PART_NUMBER SP_CH4221MEE01
J 0
(3116 888);
DISPLAY 0.297872 (3116 888);
DISPLAY INVISIBLE (3116 888);
FORCEPROP 2 LAST VALUE DIFF BUS_0.22UF
J 0
(3150 925);
DISPLAY 0.361702 (3150 925);
FORCEPROP 2 LAST VOLTAGE 6.3V
J 0
(3300 850);
DISPLAY 0.297872 (3300 850);
FORCEPROP 2 LAST TOLERANCE 20%
J 0
(3250 850);
DISPLAY 0.297872 (3250 850);
FORCEPROP 2 LAST PACK_TYPE C0201
J 0
(3175 850);
DISPLAY 0.297872 (3175 850);
FORCEPROP 1 LAST MATERIAL X6S
J 0
(3116 854);
DISPLAY 0.297872 (3116 854);
FORCEPROP 1 LAST $LOCATION C1105
J 0
(2791 942);
DISPLAY 0.468085 (2791 942);
PAINT GREEN (2791 942);
FORCEPROP 2 LASTPIN (2950 925) $PN 1
J 2
(2940 935);
DISPLAY 0.808511 (2940 935);
FORCEPROP 2 LASTPIN (3100 925) $PN 2
J 0
(3110 935);
DISPLAY 0.808511 (3110 935);
FORCEPROP 1 LAST PIN_NAMES_ROTATE TRUE
J 0
(3025 925);
DISPLAY 0.489362 (3025 925);
PAINT GREEN (3025 925);
DISPLAY INVISIBLE (3025 925);
FORCEPROP 1 LAST CDS_LMAN_SYM_OUTLINE -25,50,25,-50
J 0
(3025 925);
DISPLAY 0.468085 (3025 925);
PAINT GREEN (3025 925);
DISPLAY INVISIBLE (3025 925);
FORCEPROP 2 LAST CDS_LIB pure_quanta
J 0
(3025 925);
PAINT MONO (3025 925);
DISPLAY INVISIBLE (3025 925);
FORCEPROP 1 LAST PATH I60
J 0
(3025 925);
DISPLAY 0.723404 (3025 925);
DISPLAY INVISIBLE (3025 925);
FORCEPROP 2 LAST CDS_LOCATION C1105
J 0
(3025 975);
DISPLAY 1.021277 (3025 975);
DISPLAY INVISIBLE (3025 975);
FORCEPROP 2 LAST $SEC 1
J 0
(3025 975);
DISPLAY 0.680851 (3025 975);
PAINT MONO (3025 975);
DISPLAY INVISIBLE (3025 975);
FORCEPROP 2 LAST CDS_SEC 1
J 0
(3025 975);
DISPLAY 1.021277 (3025 975);
DISPLAY INVISIBLE (3025 975);
FORCEADD Q_CAP_DIFFBUS..2
(3025 975);
FORCEPROP 1 LAST PART_NUMBER SP_CH4221MEE01
J 0
(3141 1063);
DISPLAY 0.574468 (3141 1063);
PAINT GREEN (3141 1063);
DISPLAY INVISIBLE (3141 1063);
FORCEPROP 2 LAST VALUE DIFF BUS_0.22UF
J 0
(3150 975);
DISPLAY 0.361702 (3150 975);
FORCEPROP 1 LAST $LOCATION C1104
J 0
(2791 992);
DISPLAY 0.468085 (2791 992);
PAINT GREEN (2791 992);
FORCEPROP 2 LASTPIN (2950 975) $PN 1
J 2
(2940 985);
DISPLAY 0.808511 (2940 985);
FORCEPROP 2 LASTPIN (3100 975) $PN 2
J 0
(3110 985);
DISPLAY 0.808511 (3110 985);
FORCEPROP 2 LAST CDS_LIB pure_quanta
J 0
(3025 975);
PAINT MONO (3025 975);
DISPLAY INVISIBLE (3025 975);
FORCEPROP 1 LAST CDS_LMAN_SYM_OUTLINE -25,50,25,-50
J 0
(3025 975);
DISPLAY 0.468085 (3025 975);
PAINT GREEN (3025 975);
DISPLAY INVISIBLE (3025 975);
FORCEPROP 2 LAST TOLERANCE 20%
J 0
(3100 1025);
DISPLAY 0.553191 (3100 1025);
DISPLAY INVISIBLE (3100 1025);
FORCEPROP 2 LAST PACK_TYPE C0201
J 0
(3200 1025);
DISPLAY 0.553191 (3200 1025);
DISPLAY INVISIBLE (3200 1025);
FORCEPROP 1 LAST MATERIAL X6S
J 0
(3016 1054);
DISPLAY 0.574468 (3016 1054);
PAINT GREEN (3016 1054);
DISPLAY INVISIBLE (3016 1054);
FORCEPROP 2 LAST VOLTAGE 6.3V
J 0
(3375 1025);
DISPLAY 0.553191 (3375 1025);
DISPLAY INVISIBLE (3375 1025);
FORCEPROP 1 LAST PIN_NAMES_ROTATE TRUE
J 0
(3025 975);
DISPLAY 0.489362 (3025 975);
PAINT GREEN (3025 975);
DISPLAY INVISIBLE (3025 975);
FORCEPROP 1 LAST PATH I61
J 0
(3025 975);
DISPLAY 0.723404 (3025 975);
DISPLAY INVISIBLE (3025 975);
FORCEPROP 2 LAST CDS_LOCATION C1104
J 0
(3025 1025);
DISPLAY 1.021277 (3025 1025);
DISPLAY INVISIBLE (3025 1025);
FORCEPROP 2 LAST $SEC 1
J 0
(3025 1025);
DISPLAY 0.680851 (3025 1025);
PAINT MONO (3025 1025);
DISPLAY INVISIBLE (3025 1025);
FORCEPROP 2 LAST CDS_SEC 1
J 0
(3025 1025);
DISPLAY 1.021277 (3025 1025);
DISPLAY INVISIBLE (3025 1025);
FORCEADD Q_CAP_DIFFBUS..2
(3025 1025);
FORCEPROP 1 LAST PART_NUMBER SP_CH4221MEE01
J 0
(3141 1113);
DISPLAY 0.574468 (3141 1113);
PAINT GREEN (3141 1113);
DISPLAY INVISIBLE (3141 1113);
FORCEPROP 2 LAST VALUE DIFF BUS_0.22UF
J 0
(3150 1025);
DISPLAY 0.361702 (3150 1025);
FORCEPROP 1 LAST $LOCATION C1103
J 0
(2791 1042);
DISPLAY 0.468085 (2791 1042);
PAINT GREEN (2791 1042);
FORCEPROP 2 LASTPIN (2950 1025) $PN 1
J 2
(2940 1035);
DISPLAY 0.808511 (2940 1035);
FORCEPROP 2 LASTPIN (3100 1025) $PN 2
J 0
(3110 1035);
DISPLAY 0.808511 (3110 1035);
FORCEPROP 2 LAST CDS_LIB pure_quanta
J 0
(3025 1025);
PAINT MONO (3025 1025);
DISPLAY INVISIBLE (3025 1025);
FORCEPROP 1 LAST CDS_LMAN_SYM_OUTLINE -25,50,25,-50
J 0
(3025 1025);
DISPLAY 0.468085 (3025 1025);
PAINT GREEN (3025 1025);
DISPLAY INVISIBLE (3025 1025);
FORCEPROP 2 LAST TOLERANCE 20%
J 0
(3100 1075);
DISPLAY 0.553191 (3100 1075);
DISPLAY INVISIBLE (3100 1075);
FORCEPROP 2 LAST PACK_TYPE C0201
J 0
(3200 1075);
DISPLAY 0.553191 (3200 1075);
DISPLAY INVISIBLE (3200 1075);
FORCEPROP 1 LAST MATERIAL X6S
J 0
(3016 1104);
DISPLAY 0.574468 (3016 1104);
PAINT GREEN (3016 1104);
DISPLAY INVISIBLE (3016 1104);
FORCEPROP 2 LAST VOLTAGE 6.3V
J 0
(3375 1075);
DISPLAY 0.553191 (3375 1075);
DISPLAY INVISIBLE (3375 1075);
FORCEPROP 1 LAST PIN_NAMES_ROTATE TRUE
J 0
(3025 1025);
DISPLAY 0.489362 (3025 1025);
PAINT GREEN (3025 1025);
DISPLAY INVISIBLE (3025 1025);
FORCEPROP 1 LAST PATH I62
J 0
(3025 1025);
DISPLAY 0.723404 (3025 1025);
DISPLAY INVISIBLE (3025 1025);
FORCEPROP 2 LAST CDS_LOCATION C1103
J 0
(3025 1075);
DISPLAY 1.021277 (3025 1075);
DISPLAY INVISIBLE (3025 1075);
FORCEPROP 2 LAST $SEC 1
J 0
(3025 1075);
DISPLAY 0.680851 (3025 1075);
PAINT MONO (3025 1075);
DISPLAY INVISIBLE (3025 1075);
FORCEPROP 2 LAST CDS_SEC 1
J 0
(3025 1075);
DISPLAY 1.021277 (3025 1075);
DISPLAY INVISIBLE (3025 1075);
FORCEADD Q_CAP_DIFFBUS..2
(3025 1075);
FORCEPROP 1 LAST PART_NUMBER SP_CH4221MEE01
J 0
(3141 1163);
DISPLAY 0.574468 (3141 1163);
PAINT GREEN (3141 1163);
DISPLAY INVISIBLE (3141 1163);
FORCEPROP 2 LAST VALUE DIFF BUS_0.22UF
J 0
(3150 1075);
DISPLAY 0.361702 (3150 1075);
FORCEPROP 1 LAST $LOCATION C1102
J 0
(2791 1092);
DISPLAY 0.468085 (2791 1092);
PAINT GREEN (2791 1092);
FORCEPROP 2 LASTPIN (2950 1075) $PN 1
J 2
(2940 1085);
DISPLAY 0.808511 (2940 1085);
FORCEPROP 2 LASTPIN (3100 1075) $PN 2
J 0
(3110 1085);
DISPLAY 0.808511 (3110 1085);
FORCEPROP 2 LAST CDS_LIB pure_quanta
J 0
(3025 1075);
PAINT MONO (3025 1075);
DISPLAY INVISIBLE (3025 1075);
FORCEPROP 1 LAST CDS_LMAN_SYM_OUTLINE -25,50,25,-50
J 0
(3025 1075);
DISPLAY 0.468085 (3025 1075);
PAINT GREEN (3025 1075);
DISPLAY INVISIBLE (3025 1075);
FORCEPROP 2 LAST TOLERANCE 20%
J 0
(3100 1125);
DISPLAY 0.553191 (3100 1125);
DISPLAY INVISIBLE (3100 1125);
FORCEPROP 2 LAST PACK_TYPE C0201
J 0
(3200 1125);
DISPLAY 0.553191 (3200 1125);
DISPLAY INVISIBLE (3200 1125);
FORCEPROP 1 LAST MATERIAL X6S
J 0
(3016 1154);
DISPLAY 0.574468 (3016 1154);
PAINT GREEN (3016 1154);
DISPLAY INVISIBLE (3016 1154);
FORCEPROP 2 LAST VOLTAGE 6.3V
J 0
(3375 1125);
DISPLAY 0.553191 (3375 1125);
DISPLAY INVISIBLE (3375 1125);
FORCEPROP 1 LAST PIN_NAMES_ROTATE TRUE
J 0
(3025 1075);
DISPLAY 0.489362 (3025 1075);
PAINT GREEN (3025 1075);
DISPLAY INVISIBLE (3025 1075);
FORCEPROP 1 LAST PATH I63
J 0
(3025 1075);
DISPLAY 0.723404 (3025 1075);
DISPLAY INVISIBLE (3025 1075);
FORCEPROP 2 LAST CDS_LOCATION C1102
J 0
(3025 1125);
DISPLAY 1.021277 (3025 1125);
DISPLAY INVISIBLE (3025 1125);
FORCEPROP 2 LAST $SEC 1
J 0
(3025 1125);
DISPLAY 0.680851 (3025 1125);
PAINT MONO (3025 1125);
DISPLAY INVISIBLE (3025 1125);
FORCEPROP 2 LAST CDS_SEC 1
J 0
(3025 1125);
DISPLAY 1.021277 (3025 1125);
DISPLAY INVISIBLE (3025 1125);
FORCEADD Q_CAP_DIFFBUS..2
(3025 1175);
FORCEPROP 1 LAST PART_NUMBER SP_CH4221MEE01
J 0
(3141 1263);
DISPLAY 0.574468 (3141 1263);
PAINT GREEN (3141 1263);
DISPLAY INVISIBLE (3141 1263);
FORCEPROP 2 LAST VALUE DIFF BUS_0.22UF
J 0
(3150 1175);
DISPLAY 0.361702 (3150 1175);
FORCEPROP 1 LAST $LOCATION C1100
J 0
(2791 1192);
DISPLAY 0.468085 (2791 1192);
PAINT GREEN (2791 1192);
FORCEPROP 2 LASTPIN (2950 1175) $PN 1
J 2
(2940 1185);
DISPLAY 0.808511 (2940 1185);
FORCEPROP 2 LASTPIN (3100 1175) $PN 2
J 0
(3110 1185);
DISPLAY 0.808511 (3110 1185);
FORCEPROP 2 LAST CDS_LIB pure_quanta
J 0
(3025 1175);
PAINT MONO (3025 1175);
DISPLAY INVISIBLE (3025 1175);
FORCEPROP 1 LAST CDS_LMAN_SYM_OUTLINE -25,50,25,-50
J 0
(3025 1175);
DISPLAY 0.468085 (3025 1175);
PAINT GREEN (3025 1175);
DISPLAY INVISIBLE (3025 1175);
FORCEPROP 2 LAST TOLERANCE 20%
J 0
(3100 1225);
DISPLAY 0.553191 (3100 1225);
DISPLAY INVISIBLE (3100 1225);
FORCEPROP 2 LAST PACK_TYPE C0201
J 0
(3200 1225);
DISPLAY 0.553191 (3200 1225);
DISPLAY INVISIBLE (3200 1225);
FORCEPROP 1 LAST MATERIAL X6S
J 0
(3016 1254);
DISPLAY 0.574468 (3016 1254);
PAINT GREEN (3016 1254);
DISPLAY INVISIBLE (3016 1254);
FORCEPROP 2 LAST VOLTAGE 6.3V
J 0
(3375 1225);
DISPLAY 0.553191 (3375 1225);
DISPLAY INVISIBLE (3375 1225);
FORCEPROP 1 LAST PIN_NAMES_ROTATE TRUE
J 0
(3025 1175);
DISPLAY 0.489362 (3025 1175);
PAINT GREEN (3025 1175);
DISPLAY INVISIBLE (3025 1175);
FORCEPROP 1 LAST PATH I64
J 0
(3025 1175);
DISPLAY 0.723404 (3025 1175);
DISPLAY INVISIBLE (3025 1175);
FORCEPROP 2 LAST CDS_LOCATION C1100
J 0
(3025 1225);
DISPLAY 1.021277 (3025 1225);
DISPLAY INVISIBLE (3025 1225);
FORCEPROP 2 LAST $SEC 1
J 0
(3025 1225);
DISPLAY 0.680851 (3025 1225);
PAINT MONO (3025 1225);
DISPLAY INVISIBLE (3025 1225);
FORCEPROP 2 LAST CDS_SEC 1
J 0
(3025 1225);
DISPLAY 1.021277 (3025 1225);
DISPLAY INVISIBLE (3025 1225);
FORCEADD Q_CAP_DIFFBUS..2
(3025 1125);
FORCEPROP 1 LAST PART_NUMBER SP_CH4221MEE01
J 0
(3141 1213);
DISPLAY 0.574468 (3141 1213);
PAINT GREEN (3141 1213);
DISPLAY INVISIBLE (3141 1213);
FORCEPROP 2 LAST VALUE DIFF BUS_0.22UF
J 0
(3150 1125);
DISPLAY 0.361702 (3150 1125);
FORCEPROP 1 LAST $LOCATION C1101
J 0
(2791 1142);
DISPLAY 0.468085 (2791 1142);
PAINT GREEN (2791 1142);
FORCEPROP 2 LASTPIN (2950 1125) $PN 1
J 2
(2940 1135);
DISPLAY 0.808511 (2940 1135);
FORCEPROP 2 LASTPIN (3100 1125) $PN 2
J 0
(3110 1135);
DISPLAY 0.808511 (3110 1135);
FORCEPROP 2 LAST CDS_LIB pure_quanta
J 0
(3025 1125);
PAINT MONO (3025 1125);
DISPLAY INVISIBLE (3025 1125);
FORCEPROP 1 LAST CDS_LMAN_SYM_OUTLINE -25,50,25,-50
J 0
(3025 1125);
DISPLAY 0.468085 (3025 1125);
PAINT GREEN (3025 1125);
DISPLAY INVISIBLE (3025 1125);
FORCEPROP 2 LAST TOLERANCE 20%
J 0
(3100 1175);
DISPLAY 0.553191 (3100 1175);
DISPLAY INVISIBLE (3100 1175);
FORCEPROP 2 LAST PACK_TYPE C0201
J 0
(3200 1175);
DISPLAY 0.553191 (3200 1175);
DISPLAY INVISIBLE (3200 1175);
FORCEPROP 1 LAST MATERIAL X6S
J 0
(3016 1204);
DISPLAY 0.574468 (3016 1204);
PAINT GREEN (3016 1204);
DISPLAY INVISIBLE (3016 1204);
FORCEPROP 2 LAST VOLTAGE 6.3V
J 0
(3375 1175);
DISPLAY 0.553191 (3375 1175);
DISPLAY INVISIBLE (3375 1175);
FORCEPROP 1 LAST PIN_NAMES_ROTATE TRUE
J 0
(3025 1125);
DISPLAY 0.489362 (3025 1125);
PAINT GREEN (3025 1125);
DISPLAY INVISIBLE (3025 1125);
FORCEPROP 1 LAST PATH I65
J 0
(3025 1125);
DISPLAY 0.723404 (3025 1125);
DISPLAY INVISIBLE (3025 1125);
FORCEPROP 2 LAST CDS_LOCATION C1101
J 0
(3025 1175);
DISPLAY 1.021277 (3025 1175);
DISPLAY INVISIBLE (3025 1175);
FORCEPROP 2 LAST $SEC 1
J 0
(3025 1175);
DISPLAY 0.680851 (3025 1175);
PAINT MONO (3025 1175);
DISPLAY INVISIBLE (3025 1175);
FORCEPROP 2 LAST CDS_SEC 1
J 0
(3025 1175);
DISPLAY 1.021277 (3025 1175);
DISPLAY INVISIBLE (3025 1175);
FORCEADD Q_CAP_DIFFBUS..2
(3025 1225);
FORCEPROP 1 LAST PART_NUMBER SP_CH4221MEE01
J 0
(3141 1313);
DISPLAY 0.574468 (3141 1313);
PAINT GREEN (3141 1313);
DISPLAY INVISIBLE (3141 1313);
FORCEPROP 2 LAST VALUE DIFF BUS_0.22UF
J 0
(3150 1225);
DISPLAY 0.361702 (3150 1225);
FORCEPROP 1 LAST $LOCATION C1099
J 0
(2791 1242);
DISPLAY 0.468085 (2791 1242);
PAINT GREEN (2791 1242);
FORCEPROP 2 LASTPIN (2950 1225) $PN 1
J 2
(2940 1235);
DISPLAY 0.808511 (2940 1235);
FORCEPROP 2 LASTPIN (3100 1225) $PN 2
J 0
(3110 1235);
DISPLAY 0.808511 (3110 1235);
FORCEPROP 2 LAST CDS_LIB pure_quanta
J 0
(3025 1225);
PAINT MONO (3025 1225);
DISPLAY INVISIBLE (3025 1225);
FORCEPROP 1 LAST CDS_LMAN_SYM_OUTLINE -25,50,25,-50
J 0
(3025 1225);
DISPLAY 0.468085 (3025 1225);
PAINT GREEN (3025 1225);
DISPLAY INVISIBLE (3025 1225);
FORCEPROP 2 LAST TOLERANCE 20%
J 0
(3100 1275);
DISPLAY 0.553191 (3100 1275);
DISPLAY INVISIBLE (3100 1275);
FORCEPROP 2 LAST PACK_TYPE C0201
J 0
(3200 1275);
DISPLAY 0.553191 (3200 1275);
DISPLAY INVISIBLE (3200 1275);
FORCEPROP 1 LAST MATERIAL X6S
J 0
(3016 1304);
DISPLAY 0.574468 (3016 1304);
PAINT GREEN (3016 1304);
DISPLAY INVISIBLE (3016 1304);
FORCEPROP 2 LAST VOLTAGE 6.3V
J 0
(3375 1275);
DISPLAY 0.553191 (3375 1275);
DISPLAY INVISIBLE (3375 1275);
FORCEPROP 1 LAST PIN_NAMES_ROTATE TRUE
J 0
(3025 1225);
DISPLAY 0.489362 (3025 1225);
PAINT GREEN (3025 1225);
DISPLAY INVISIBLE (3025 1225);
FORCEPROP 1 LAST PATH I66
J 0
(3025 1225);
DISPLAY 0.723404 (3025 1225);
DISPLAY INVISIBLE (3025 1225);
FORCEPROP 2 LAST CDS_LOCATION C1099
J 0
(3025 1275);
DISPLAY 1.021277 (3025 1275);
DISPLAY INVISIBLE (3025 1275);
FORCEPROP 2 LAST $SEC 1
J 0
(3025 1275);
DISPLAY 0.680851 (3025 1275);
PAINT MONO (3025 1275);
DISPLAY INVISIBLE (3025 1275);
FORCEPROP 2 LAST CDS_SEC 1
J 0
(3025 1275);
DISPLAY 1.021277 (3025 1275);
DISPLAY INVISIBLE (3025 1275);
FORCEADD Q_CAP_DIFFBUS..2
(3025 1275);
FORCEPROP 1 LAST PART_NUMBER SP_CH4221MEE01
J 0
(3141 1363);
DISPLAY 0.574468 (3141 1363);
PAINT GREEN (3141 1363);
DISPLAY INVISIBLE (3141 1363);
FORCEPROP 2 LAST VALUE DIFF BUS_0.22UF
J 0
(3150 1275);
DISPLAY 0.361702 (3150 1275);
FORCEPROP 1 LAST $LOCATION C1098
J 0
(2791 1292);
DISPLAY 0.468085 (2791 1292);
PAINT GREEN (2791 1292);
FORCEPROP 2 LASTPIN (2950 1275) $PN 1
J 2
(2940 1285);
DISPLAY 0.808511 (2940 1285);
FORCEPROP 2 LASTPIN (3100 1275) $PN 2
J 0
(3110 1285);
DISPLAY 0.808511 (3110 1285);
FORCEPROP 2 LAST CDS_LIB pure_quanta
J 0
(3025 1275);
PAINT MONO (3025 1275);
DISPLAY INVISIBLE (3025 1275);
FORCEPROP 1 LAST CDS_LMAN_SYM_OUTLINE -25,50,25,-50
J 0
(3025 1275);
DISPLAY 0.468085 (3025 1275);
PAINT GREEN (3025 1275);
DISPLAY INVISIBLE (3025 1275);
FORCEPROP 2 LAST TOLERANCE 20%
J 0
(3100 1325);
DISPLAY 0.553191 (3100 1325);
DISPLAY INVISIBLE (3100 1325);
FORCEPROP 2 LAST PACK_TYPE C0201
J 0
(3200 1325);
DISPLAY 0.553191 (3200 1325);
DISPLAY INVISIBLE (3200 1325);
FORCEPROP 1 LAST MATERIAL X6S
J 0
(3016 1354);
DISPLAY 0.574468 (3016 1354);
PAINT GREEN (3016 1354);
DISPLAY INVISIBLE (3016 1354);
FORCEPROP 2 LAST VOLTAGE 6.3V
J 0
(3375 1325);
DISPLAY 0.553191 (3375 1325);
DISPLAY INVISIBLE (3375 1325);
FORCEPROP 1 LAST PIN_NAMES_ROTATE TRUE
J 0
(3025 1275);
DISPLAY 0.489362 (3025 1275);
PAINT GREEN (3025 1275);
DISPLAY INVISIBLE (3025 1275);
FORCEPROP 1 LAST PATH I67
J 0
(3025 1275);
DISPLAY 0.723404 (3025 1275);
DISPLAY INVISIBLE (3025 1275);
FORCEPROP 2 LAST CDS_LOCATION C1098
J 0
(3025 1325);
DISPLAY 1.021277 (3025 1325);
DISPLAY INVISIBLE (3025 1325);
FORCEPROP 2 LAST $SEC 1
J 0
(3025 1325);
DISPLAY 0.680851 (3025 1325);
PAINT MONO (3025 1325);
DISPLAY INVISIBLE (3025 1325);
FORCEPROP 2 LAST CDS_SEC 1
J 0
(3025 1325);
DISPLAY 1.021277 (3025 1325);
DISPLAY INVISIBLE (3025 1325);
FORCEADD Q_CAP_DIFFBUS..2
(3025 1325);
FORCEPROP 1 LAST PART_NUMBER SP_CH4221MEE01
J 0
(3116 1288);
DISPLAY 0.297872 (3116 1288);
DISPLAY INVISIBLE (3116 1288);
FORCEPROP 0 LAST VALUE DIFF BUS_0.22UF
J 0
(3150 1325);
DISPLAY 0.361702 (3150 1325);
FORCEPROP 1 LAST $LOCATION C1996
J 0
(2791 1342);
DISPLAY 0.468085 (2791 1342);
PAINT GREEN (2791 1342);
FORCEPROP 2 LASTPIN (2950 1325) $PN 1
J 2
(2940 1335);
DISPLAY 0.808511 (2940 1335);
FORCEPROP 2 LASTPIN (3100 1325) $PN 2
J 0
(3110 1335);
DISPLAY 0.808511 (3110 1335);
FORCEPROP 2 LAST CDS_LIB pure_quanta
J 0
(3025 1325);
PAINT MONO (3025 1325);
DISPLAY INVISIBLE (3025 1325);
FORCEPROP 1 LAST CDS_LMAN_SYM_OUTLINE -25,50,25,-50
J 0
(3025 1325);
DISPLAY 0.468085 (3025 1325);
PAINT GREEN (3025 1325);
DISPLAY INVISIBLE (3025 1325);
FORCEPROP 1 LAST PIN_NAMES_ROTATE TRUE
J 0
(3025 1325);
DISPLAY 0.489362 (3025 1325);
PAINT GREEN (3025 1325);
DISPLAY INVISIBLE (3025 1325);
FORCEPROP 1 LAST MATERIAL X6S
J 0
(3116 1254);
DISPLAY 0.297872 (3116 1254);
DISPLAY INVISIBLE (3116 1254);
FORCEPROP 0 LAST PACK_TYPE C0201
J 0
(3175 1250);
DISPLAY 0.297872 (3175 1250);
DISPLAY INVISIBLE (3175 1250);
FORCEPROP 0 LAST TOLERANCE 20%
J 0
(3250 1250);
DISPLAY 0.297872 (3250 1250);
DISPLAY INVISIBLE (3250 1250);
FORCEPROP 0 LAST VOLTAGE 6.3V
J 0
(3300 1250);
DISPLAY 0.297872 (3300 1250);
DISPLAY INVISIBLE (3300 1250);
FORCEPROP 1 LAST PATH I68
J 0
(3025 1325);
DISPLAY 0.723404 (3025 1325);
DISPLAY INVISIBLE (3025 1325);
FORCEPROP 2 LAST CDS_LOCATION C1996
J 0
(3025 1375);
DISPLAY 1.021277 (3025 1375);
DISPLAY INVISIBLE (3025 1375);
FORCEPROP 2 LAST $SEC 1
J 0
(3025 1375);
DISPLAY 0.680851 (3025 1375);
PAINT MONO (3025 1375);
DISPLAY INVISIBLE (3025 1375);
FORCEPROP 2 LAST CDS_SEC 1
J 0
(3025 1375);
DISPLAY 1.021277 (3025 1375);
DISPLAY INVISIBLE (3025 1375);
FORCEADD Q_CAP_DIFFBUS..2
(3025 1375);
FORCEPROP 1 LAST PART_NUMBER SP_CH4221MEE01
J 0
(3141 1463);
DISPLAY 0.574468 (3141 1463);
PAINT GREEN (3141 1463);
DISPLAY INVISIBLE (3141 1463);
FORCEPROP 2 LAST VALUE DIFF BUS_0.22UF
J 0
(3150 1375);
DISPLAY 0.361702 (3150 1375);
FORCEPROP 1 LAST $LOCATION C1995
J 0
(2791 1392);
DISPLAY 0.468085 (2791 1392);
PAINT GREEN (2791 1392);
FORCEPROP 2 LASTPIN (2950 1375) $PN 1
J 2
(2940 1385);
DISPLAY 0.808511 (2940 1385);
FORCEPROP 2 LASTPIN (3100 1375) $PN 2
J 0
(3110 1385);
DISPLAY 0.808511 (3110 1385);
FORCEPROP 2 LAST CDS_LIB pure_quanta
J 0
(3025 1375);
PAINT MONO (3025 1375);
DISPLAY INVISIBLE (3025 1375);
FORCEPROP 1 LAST CDS_LMAN_SYM_OUTLINE -25,50,25,-50
J 0
(3025 1375);
DISPLAY 0.468085 (3025 1375);
PAINT GREEN (3025 1375);
DISPLAY INVISIBLE (3025 1375);
FORCEPROP 2 LAST TOLERANCE 20%
J 0
(3100 1425);
DISPLAY 0.553191 (3100 1425);
DISPLAY INVISIBLE (3100 1425);
FORCEPROP 2 LAST PACK_TYPE C0201
J 0
(3200 1425);
DISPLAY 0.553191 (3200 1425);
DISPLAY INVISIBLE (3200 1425);
FORCEPROP 1 LAST MATERIAL X6S
J 0
(3016 1454);
DISPLAY 0.574468 (3016 1454);
PAINT GREEN (3016 1454);
DISPLAY INVISIBLE (3016 1454);
FORCEPROP 2 LAST VOLTAGE 6.3V
J 0
(3375 1425);
DISPLAY 0.553191 (3375 1425);
DISPLAY INVISIBLE (3375 1425);
FORCEPROP 1 LAST PIN_NAMES_ROTATE TRUE
J 0
(3025 1375);
DISPLAY 0.489362 (3025 1375);
PAINT GREEN (3025 1375);
DISPLAY INVISIBLE (3025 1375);
FORCEPROP 1 LAST PATH I69
J 0
(3025 1375);
DISPLAY 0.723404 (3025 1375);
DISPLAY INVISIBLE (3025 1375);
FORCEPROP 2 LAST CDS_LOCATION C1995
J 0
(3025 1425);
DISPLAY 1.021277 (3025 1425);
DISPLAY INVISIBLE (3025 1425);
FORCEPROP 2 LAST $SEC 1
J 0
(3025 1425);
DISPLAY 0.680851 (3025 1425);
PAINT MONO (3025 1425);
DISPLAY INVISIBLE (3025 1425);
FORCEPROP 2 LAST CDS_SEC 1
J 0
(3025 1425);
DISPLAY 1.021277 (3025 1425);
DISPLAY INVISIBLE (3025 1425);
FORCEADD OFFPAGE..1
(-2450 1175);
FORCEPROP 2 LAST $XR0 190 
J 0
(-2732 1175);
DISPLAY 0.638298 (-2732 1175);
PAINT MONO (-2732 1175);
FORCEPROP 2 LAST CDS_LIB standard
J 0
(-2450 1175);
PAINT MONO (-2450 1175);
DISPLAY INVISIBLE (-2450 1175);
FORCEPROP 1 LAST OFFPAGE TRUE
J 0
(-2125 1050);
DISPLAY 0.872340 (-2125 1050);
DISPLAY INVISIBLE (-2125 1050);
FORCEPROP 1 LAST COMMENT_BODY TRUE
J 0
(-2325 1075);
DISPLAY 0.872340 (-2325 1075);
PAINT GREEN (-2325 1075);
DISPLAY INVISIBLE (-2325 1075);
FORCEPROP 2 LAST PATH I7
J 0
(-2725 1225);
DISPLAY 1.021277 (-2725 1225);
DISPLAY INVISIBLE (-2725 1225);
FORCEADD Q_CAP_DIFFBUS..2
(3025 1425);
FORCEPROP 1 LAST PART_NUMBER SP_CH4221MEE01
J 0
(3141 1513);
DISPLAY 0.574468 (3141 1513);
PAINT GREEN (3141 1513);
DISPLAY INVISIBLE (3141 1513);
FORCEPROP 2 LAST VALUE DIFF BUS_0.22UF
J 0
(3150 1425);
DISPLAY 0.361702 (3150 1425);
FORCEPROP 1 LAST $LOCATION C1994
J 0
(2791 1442);
DISPLAY 0.468085 (2791 1442);
PAINT GREEN (2791 1442);
FORCEPROP 2 LASTPIN (2950 1425) $PN 1
J 2
(2940 1435);
DISPLAY 0.808511 (2940 1435);
FORCEPROP 2 LASTPIN (3100 1425) $PN 2
J 0
(3110 1435);
DISPLAY 0.808511 (3110 1435);
FORCEPROP 1 LAST PIN_NAMES_ROTATE TRUE
J 0
(3025 1425);
DISPLAY 0.489362 (3025 1425);
PAINT GREEN (3025 1425);
DISPLAY INVISIBLE (3025 1425);
FORCEPROP 2 LAST VOLTAGE 6.3V
J 0
(3375 1475);
DISPLAY 0.553191 (3375 1475);
DISPLAY INVISIBLE (3375 1475);
FORCEPROP 1 LAST MATERIAL X6S
J 0
(3016 1504);
DISPLAY 0.574468 (3016 1504);
PAINT GREEN (3016 1504);
DISPLAY INVISIBLE (3016 1504);
FORCEPROP 2 LAST PACK_TYPE C0201
J 0
(3200 1475);
DISPLAY 0.553191 (3200 1475);
DISPLAY INVISIBLE (3200 1475);
FORCEPROP 2 LAST TOLERANCE 20%
J 0
(3100 1475);
DISPLAY 0.553191 (3100 1475);
DISPLAY INVISIBLE (3100 1475);
FORCEPROP 1 LAST CDS_LMAN_SYM_OUTLINE -25,50,25,-50
J 0
(3025 1425);
DISPLAY 0.468085 (3025 1425);
PAINT GREEN (3025 1425);
DISPLAY INVISIBLE (3025 1425);
FORCEPROP 2 LAST CDS_LIB pure_quanta
J 0
(3025 1425);
PAINT MONO (3025 1425);
DISPLAY INVISIBLE (3025 1425);
FORCEPROP 1 LAST PATH I70
J 0
(3025 1425);
DISPLAY 0.723404 (3025 1425);
DISPLAY INVISIBLE (3025 1425);
FORCEPROP 2 LAST CDS_LOCATION C1994
J 0
(3025 1475);
DISPLAY 1.021277 (3025 1475);
DISPLAY INVISIBLE (3025 1475);
FORCEPROP 2 LAST $SEC 1
J 0
(3025 1475);
DISPLAY 0.680851 (3025 1475);
PAINT MONO (3025 1475);
DISPLAY INVISIBLE (3025 1475);
FORCEPROP 2 LAST CDS_SEC 1
J 0
(3025 1475);
DISPLAY 1.021277 (3025 1475);
DISPLAY INVISIBLE (3025 1475);
FORCEADD Q_CAP_DIFFBUS..2
(3025 1475);
FORCEPROP 1 LAST PART_NUMBER SP_CH4221MEE01
J 0
(3141 1563);
DISPLAY 0.574468 (3141 1563);
PAINT GREEN (3141 1563);
DISPLAY INVISIBLE (3141 1563);
FORCEPROP 2 LAST VALUE DIFF BUS_0.22UF
J 0
(3150 1475);
DISPLAY 0.361702 (3150 1475);
FORCEPROP 1 LAST $LOCATION C1993
J 0
(2791 1492);
DISPLAY 0.468085 (2791 1492);
PAINT GREEN (2791 1492);
FORCEPROP 2 LASTPIN (2950 1475) $PN 1
J 2
(2940 1485);
DISPLAY 0.808511 (2940 1485);
FORCEPROP 2 LASTPIN (3100 1475) $PN 2
J 0
(3110 1485);
DISPLAY 0.808511 (3110 1485);
FORCEPROP 1 LAST PIN_NAMES_ROTATE TRUE
J 0
(3025 1475);
DISPLAY 0.489362 (3025 1475);
PAINT GREEN (3025 1475);
DISPLAY INVISIBLE (3025 1475);
FORCEPROP 2 LAST VOLTAGE 6.3V
J 0
(3375 1525);
DISPLAY 0.553191 (3375 1525);
DISPLAY INVISIBLE (3375 1525);
FORCEPROP 1 LAST MATERIAL X6S
J 0
(3016 1554);
DISPLAY 0.574468 (3016 1554);
PAINT GREEN (3016 1554);
DISPLAY INVISIBLE (3016 1554);
FORCEPROP 2 LAST PACK_TYPE C0201
J 0
(3200 1525);
DISPLAY 0.553191 (3200 1525);
DISPLAY INVISIBLE (3200 1525);
FORCEPROP 2 LAST TOLERANCE 20%
J 0
(3100 1525);
DISPLAY 0.553191 (3100 1525);
DISPLAY INVISIBLE (3100 1525);
FORCEPROP 1 LAST CDS_LMAN_SYM_OUTLINE -25,50,25,-50
J 0
(3025 1475);
DISPLAY 0.468085 (3025 1475);
PAINT GREEN (3025 1475);
DISPLAY INVISIBLE (3025 1475);
FORCEPROP 2 LAST CDS_LIB pure_quanta
J 0
(3025 1475);
PAINT MONO (3025 1475);
DISPLAY INVISIBLE (3025 1475);
FORCEPROP 1 LAST PATH I71
J 0
(3025 1475);
DISPLAY 0.723404 (3025 1475);
DISPLAY INVISIBLE (3025 1475);
FORCEPROP 2 LAST CDS_LOCATION C1993
J 0
(3025 1525);
DISPLAY 1.021277 (3025 1525);
DISPLAY INVISIBLE (3025 1525);
FORCEPROP 2 LAST $SEC 1
J 0
(3025 1525);
DISPLAY 0.680851 (3025 1525);
PAINT MONO (3025 1525);
DISPLAY INVISIBLE (3025 1525);
FORCEPROP 2 LAST CDS_SEC 1
J 0
(3025 1525);
DISPLAY 1.021277 (3025 1525);
DISPLAY INVISIBLE (3025 1525);
FORCEADD Q_CAP_DIFFBUS..2
(3025 1525);
FORCEPROP 1 LAST PART_NUMBER SP_CH4221MEE01
J 0
(3141 1613);
DISPLAY 0.574468 (3141 1613);
PAINT GREEN (3141 1613);
DISPLAY INVISIBLE (3141 1613);
FORCEPROP 2 LAST VALUE DIFF BUS_0.22UF
J 0
(3150 1525);
DISPLAY 0.361702 (3150 1525);
FORCEPROP 1 LAST $LOCATION C1992
J 0
(2791 1542);
DISPLAY 0.468085 (2791 1542);
PAINT GREEN (2791 1542);
FORCEPROP 2 LASTPIN (2950 1525) $PN 1
J 2
(2940 1535);
DISPLAY 0.808511 (2940 1535);
FORCEPROP 2 LASTPIN (3100 1525) $PN 2
J 0
(3110 1535);
DISPLAY 0.808511 (3110 1535);
FORCEPROP 1 LAST PIN_NAMES_ROTATE TRUE
J 0
(3025 1525);
DISPLAY 0.489362 (3025 1525);
PAINT GREEN (3025 1525);
DISPLAY INVISIBLE (3025 1525);
FORCEPROP 2 LAST VOLTAGE 6.3V
J 0
(3375 1575);
DISPLAY 0.553191 (3375 1575);
DISPLAY INVISIBLE (3375 1575);
FORCEPROP 1 LAST MATERIAL X6S
J 0
(3016 1604);
DISPLAY 0.574468 (3016 1604);
PAINT GREEN (3016 1604);
DISPLAY INVISIBLE (3016 1604);
FORCEPROP 2 LAST PACK_TYPE C0201
J 0
(3200 1575);
DISPLAY 0.553191 (3200 1575);
DISPLAY INVISIBLE (3200 1575);
FORCEPROP 2 LAST TOLERANCE 20%
J 0
(3100 1575);
DISPLAY 0.553191 (3100 1575);
DISPLAY INVISIBLE (3100 1575);
FORCEPROP 1 LAST CDS_LMAN_SYM_OUTLINE -25,50,25,-50
J 0
(3025 1525);
DISPLAY 0.468085 (3025 1525);
PAINT GREEN (3025 1525);
DISPLAY INVISIBLE (3025 1525);
FORCEPROP 2 LAST CDS_LIB pure_quanta
J 0
(3025 1525);
PAINT MONO (3025 1525);
DISPLAY INVISIBLE (3025 1525);
FORCEPROP 1 LAST PATH I72
J 0
(3025 1525);
DISPLAY 0.723404 (3025 1525);
DISPLAY INVISIBLE (3025 1525);
FORCEPROP 2 LAST CDS_LOCATION C1992
J 0
(3025 1575);
DISPLAY 1.021277 (3025 1575);
DISPLAY INVISIBLE (3025 1575);
FORCEPROP 2 LAST $SEC 1
J 0
(3025 1575);
DISPLAY 0.680851 (3025 1575);
PAINT MONO (3025 1575);
DISPLAY INVISIBLE (3025 1575);
FORCEPROP 2 LAST CDS_SEC 1
J 0
(3025 1575);
DISPLAY 1.021277 (3025 1575);
DISPLAY INVISIBLE (3025 1575);
FORCEADD Q_CAP_DIFFBUS..2
(3025 1575);
FORCEPROP 1 LAST PART_NUMBER SP_CH4221MEE01
J 0
(3141 1663);
DISPLAY 0.574468 (3141 1663);
PAINT GREEN (3141 1663);
DISPLAY INVISIBLE (3141 1663);
FORCEPROP 2 LAST VALUE DIFF BUS_0.22UF
J 0
(3150 1575);
DISPLAY 0.361702 (3150 1575);
FORCEPROP 1 LAST $LOCATION C1991
J 0
(2791 1592);
DISPLAY 0.468085 (2791 1592);
PAINT GREEN (2791 1592);
FORCEPROP 2 LASTPIN (2950 1575) $PN 1
J 2
(2940 1585);
DISPLAY 0.808511 (2940 1585);
FORCEPROP 2 LASTPIN (3100 1575) $PN 2
J 0
(3110 1585);
DISPLAY 0.808511 (3110 1585);
FORCEPROP 1 LAST PIN_NAMES_ROTATE TRUE
J 0
(3025 1575);
DISPLAY 0.489362 (3025 1575);
PAINT GREEN (3025 1575);
DISPLAY INVISIBLE (3025 1575);
FORCEPROP 2 LAST VOLTAGE 6.3V
J 0
(3375 1625);
DISPLAY 0.553191 (3375 1625);
DISPLAY INVISIBLE (3375 1625);
FORCEPROP 1 LAST MATERIAL X6S
J 0
(3016 1654);
DISPLAY 0.574468 (3016 1654);
PAINT GREEN (3016 1654);
DISPLAY INVISIBLE (3016 1654);
FORCEPROP 2 LAST PACK_TYPE C0201
J 0
(3200 1625);
DISPLAY 0.553191 (3200 1625);
DISPLAY INVISIBLE (3200 1625);
FORCEPROP 2 LAST TOLERANCE 20%
J 0
(3100 1625);
DISPLAY 0.553191 (3100 1625);
DISPLAY INVISIBLE (3100 1625);
FORCEPROP 1 LAST CDS_LMAN_SYM_OUTLINE -25,50,25,-50
J 0
(3025 1575);
DISPLAY 0.468085 (3025 1575);
PAINT GREEN (3025 1575);
DISPLAY INVISIBLE (3025 1575);
FORCEPROP 2 LAST CDS_LIB pure_quanta
J 0
(3025 1575);
PAINT MONO (3025 1575);
DISPLAY INVISIBLE (3025 1575);
FORCEPROP 1 LAST PATH I73
J 0
(3025 1575);
DISPLAY 0.723404 (3025 1575);
DISPLAY INVISIBLE (3025 1575);
FORCEPROP 2 LAST CDS_LOCATION C1991
J 0
(3025 1625);
DISPLAY 1.021277 (3025 1625);
DISPLAY INVISIBLE (3025 1625);
FORCEPROP 2 LAST $SEC 1
J 0
(3025 1625);
DISPLAY 0.680851 (3025 1625);
PAINT MONO (3025 1625);
DISPLAY INVISIBLE (3025 1625);
FORCEPROP 2 LAST CDS_SEC 1
J 0
(3025 1625);
DISPLAY 1.021277 (3025 1625);
DISPLAY INVISIBLE (3025 1625);
FORCEADD Q_CAP_DIFFBUS..2
(3025 1625);
FORCEPROP 1 LAST PART_NUMBER SP_CH4221MEE01
J 0
(3141 1713);
DISPLAY 0.574468 (3141 1713);
PAINT GREEN (3141 1713);
DISPLAY INVISIBLE (3141 1713);
FORCEPROP 2 LAST VALUE DIFF BUS_0.22UF
J 0
(3150 1625);
DISPLAY 0.361702 (3150 1625);
FORCEPROP 1 LAST $LOCATION C1990
J 0
(2791 1642);
DISPLAY 0.468085 (2791 1642);
PAINT GREEN (2791 1642);
FORCEPROP 2 LASTPIN (2950 1625) $PN 1
J 2
(2940 1635);
DISPLAY 0.808511 (2940 1635);
FORCEPROP 2 LASTPIN (3100 1625) $PN 2
J 0
(3110 1635);
DISPLAY 0.808511 (3110 1635);
FORCEPROP 1 LAST PIN_NAMES_ROTATE TRUE
J 0
(3025 1625);
DISPLAY 0.489362 (3025 1625);
PAINT GREEN (3025 1625);
DISPLAY INVISIBLE (3025 1625);
FORCEPROP 2 LAST VOLTAGE 6.3V
J 0
(3375 1675);
DISPLAY 0.553191 (3375 1675);
DISPLAY INVISIBLE (3375 1675);
FORCEPROP 1 LAST MATERIAL X6S
J 0
(3016 1704);
DISPLAY 0.574468 (3016 1704);
PAINT GREEN (3016 1704);
DISPLAY INVISIBLE (3016 1704);
FORCEPROP 2 LAST PACK_TYPE C0201
J 0
(3200 1675);
DISPLAY 0.553191 (3200 1675);
DISPLAY INVISIBLE (3200 1675);
FORCEPROP 2 LAST TOLERANCE 20%
J 0
(3100 1675);
DISPLAY 0.553191 (3100 1675);
DISPLAY INVISIBLE (3100 1675);
FORCEPROP 1 LAST CDS_LMAN_SYM_OUTLINE -25,50,25,-50
J 0
(3025 1625);
DISPLAY 0.468085 (3025 1625);
PAINT GREEN (3025 1625);
DISPLAY INVISIBLE (3025 1625);
FORCEPROP 2 LAST CDS_LIB pure_quanta
J 0
(3025 1625);
PAINT MONO (3025 1625);
DISPLAY INVISIBLE (3025 1625);
FORCEPROP 1 LAST PATH I74
J 0
(3025 1625);
DISPLAY 0.723404 (3025 1625);
DISPLAY INVISIBLE (3025 1625);
FORCEPROP 2 LAST CDS_LOCATION C1990
J 0
(3025 1675);
DISPLAY 1.021277 (3025 1675);
DISPLAY INVISIBLE (3025 1675);
FORCEPROP 2 LAST $SEC 1
J 0
(3025 1675);
DISPLAY 0.680851 (3025 1675);
PAINT MONO (3025 1675);
DISPLAY INVISIBLE (3025 1675);
FORCEPROP 2 LAST CDS_SEC 1
J 0
(3025 1675);
DISPLAY 1.021277 (3025 1675);
DISPLAY INVISIBLE (3025 1675);
FORCEADD Q_CAP_DIFFBUS..2
(3025 1675);
FORCEPROP 1 LAST PART_NUMBER SP_CH4221MEE01
J 0
(3141 1763);
DISPLAY 0.574468 (3141 1763);
PAINT GREEN (3141 1763);
DISPLAY INVISIBLE (3141 1763);
FORCEPROP 2 LAST VALUE DIFF BUS_0.22UF
J 0
(3150 1675);
DISPLAY 0.361702 (3150 1675);
FORCEPROP 1 LAST $LOCATION C1989
J 0
(2791 1692);
DISPLAY 0.468085 (2791 1692);
PAINT GREEN (2791 1692);
FORCEPROP 2 LASTPIN (2950 1675) $PN 1
J 2
(2940 1685);
DISPLAY 0.808511 (2940 1685);
FORCEPROP 2 LASTPIN (3100 1675) $PN 2
J 0
(3110 1685);
DISPLAY 0.808511 (3110 1685);
FORCEPROP 2 LAST TOLERANCE 20%
J 0
(3100 1725);
DISPLAY 0.553191 (3100 1725);
DISPLAY INVISIBLE (3100 1725);
FORCEPROP 2 LAST PACK_TYPE C0201
J 0
(3200 1725);
DISPLAY 0.553191 (3200 1725);
DISPLAY INVISIBLE (3200 1725);
FORCEPROP 1 LAST MATERIAL X6S
J 0
(3016 1754);
DISPLAY 0.574468 (3016 1754);
PAINT GREEN (3016 1754);
DISPLAY INVISIBLE (3016 1754);
FORCEPROP 2 LAST VOLTAGE 6.3V
J 0
(3375 1725);
DISPLAY 0.553191 (3375 1725);
DISPLAY INVISIBLE (3375 1725);
FORCEPROP 1 LAST PIN_NAMES_ROTATE TRUE
J 0
(3025 1675);
DISPLAY 0.489362 (3025 1675);
PAINT GREEN (3025 1675);
DISPLAY INVISIBLE (3025 1675);
FORCEPROP 2 LAST CDS_LIB pure_quanta
J 0
(3025 1675);
PAINT MONO (3025 1675);
DISPLAY INVISIBLE (3025 1675);
FORCEPROP 1 LAST CDS_LMAN_SYM_OUTLINE -25,50,25,-50
J 0
(3025 1675);
DISPLAY 0.468085 (3025 1675);
PAINT GREEN (3025 1675);
DISPLAY INVISIBLE (3025 1675);
FORCEPROP 1 LAST PATH I75
J 0
(3025 1675);
DISPLAY 0.723404 (3025 1675);
DISPLAY INVISIBLE (3025 1675);
FORCEPROP 2 LAST CDS_LOCATION C1989
J 0
(3025 1725);
DISPLAY 1.021277 (3025 1725);
DISPLAY INVISIBLE (3025 1725);
FORCEPROP 2 LAST $SEC 1
J 0
(3025 1725);
DISPLAY 0.680851 (3025 1725);
PAINT MONO (3025 1725);
DISPLAY INVISIBLE (3025 1725);
FORCEPROP 2 LAST CDS_SEC 1
J 0
(3025 1725);
DISPLAY 1.021277 (3025 1725);
DISPLAY INVISIBLE (3025 1725);
FORCEADD Q_CAP_DIFFBUS..2
(3025 1725);
FORCEPROP 1 LAST PART_NUMBER SP_CH4221MEE01
J 0
(3141 1813);
DISPLAY 0.574468 (3141 1813);
PAINT GREEN (3141 1813);
DISPLAY INVISIBLE (3141 1813);
FORCEPROP 2 LAST VALUE DIFF BUS_0.22UF
J 0
(3150 1725);
DISPLAY 0.361702 (3150 1725);
FORCEPROP 1 LAST $LOCATION C2078
J 0
(2800 1750);
DISPLAY 0.468085 (2800 1750);
PAINT GREEN (2800 1750);
FORCEPROP 0 LASTPIN (2950 1725) $PN 1
J 2
(2940 1735);
DISPLAY 0.680851 (2940 1735);
PAINT MONO (2940 1735);
FORCEPROP 0 LASTPIN (3100 1725) $PN 2
J 0
(3110 1735);
DISPLAY 0.680851 (3110 1735);
PAINT MONO (3110 1735);
FORCEPROP 2 LAST CDS_LIB pure_quanta
J 0
(3025 1725);
DISPLAY INVISIBLE (3025 1725);
FORCEPROP 1 LAST CDS_LMAN_SYM_OUTLINE -25,50,25,-50
J 0
(3025 1725);
DISPLAY 0.468085 (3025 1725);
PAINT GREEN (3025 1725);
DISPLAY INVISIBLE (3025 1725);
FORCEPROP 1 LAST PIN_NAMES_ROTATE TRUE
J 0
(3025 1725);
DISPLAY 0.489362 (3025 1725);
PAINT GREEN (3025 1725);
DISPLAY INVISIBLE (3025 1725);
FORCEPROP 2 LAST VOLTAGE 6.3V
J 0
(3375 1775);
DISPLAY 0.553191 (3375 1775);
DISPLAY INVISIBLE (3375 1775);
FORCEPROP 1 LAST MATERIAL X6S
J 0
(3016 1804);
DISPLAY 0.574468 (3016 1804);
PAINT GREEN (3016 1804);
DISPLAY INVISIBLE (3016 1804);
FORCEPROP 2 LAST PACK_TYPE C0201
J 0
(3200 1775);
DISPLAY 0.553191 (3200 1775);
DISPLAY INVISIBLE (3200 1775);
FORCEPROP 2 LAST TOLERANCE 20%
J 0
(3100 1775);
DISPLAY 0.553191 (3100 1775);
DISPLAY INVISIBLE (3100 1775);
FORCEPROP 1 LAST PATH I76
J 0
(3025 1725);
DISPLAY 0.723404 (3025 1725);
DISPLAY INVISIBLE (3025 1725);
FORCEPROP 0 LAST CDS_LOCATION C2078
J 0
(3150 1750);
DISPLAY 1.021277 (3150 1750);
DISPLAY INVISIBLE (3150 1750);
FORCEPROP 0 LAST $SEC 1
J 0
(3150 1750);
DISPLAY 0.680851 (3150 1750);
PAINT MONO (3150 1750);
DISPLAY INVISIBLE (3150 1750);
FORCEPROP 0 LAST CDS_SEC 1
J 0
(3150 1750);
DISPLAY 1.021277 (3150 1750);
DISPLAY INVISIBLE (3150 1750);
FORCEADD Q_CAP_DIFFBUS..2
(3025 1775);
FORCEPROP 1 LAST PART_NUMBER SP_CH4221MEE01
J 0
(3141 1863);
DISPLAY 0.574468 (3141 1863);
PAINT GREEN (3141 1863);
DISPLAY INVISIBLE (3141 1863);
FORCEPROP 2 LAST VALUE DIFF BUS_0.22UF
J 0
(3150 1775);
DISPLAY 0.361702 (3150 1775);
FORCEPROP 1 LAST $LOCATION C2077
J 0
(2800 1800);
DISPLAY 0.468085 (2800 1800);
PAINT GREEN (2800 1800);
FORCEPROP 0 LASTPIN (2950 1775) $PN 1
J 2
(2940 1785);
DISPLAY 0.680851 (2940 1785);
PAINT MONO (2940 1785);
FORCEPROP 0 LASTPIN (3100 1775) $PN 2
J 0
(3110 1785);
DISPLAY 0.680851 (3110 1785);
PAINT MONO (3110 1785);
FORCEPROP 2 LAST CDS_LIB pure_quanta
J 0
(3025 1775);
DISPLAY INVISIBLE (3025 1775);
FORCEPROP 1 LAST CDS_LMAN_SYM_OUTLINE -25,50,25,-50
J 0
(3025 1775);
DISPLAY 0.468085 (3025 1775);
PAINT GREEN (3025 1775);
DISPLAY INVISIBLE (3025 1775);
FORCEPROP 2 LAST TOLERANCE 20%
J 0
(3100 1825);
DISPLAY 0.553191 (3100 1825);
DISPLAY INVISIBLE (3100 1825);
FORCEPROP 2 LAST PACK_TYPE C0201
J 0
(3200 1825);
DISPLAY 0.553191 (3200 1825);
DISPLAY INVISIBLE (3200 1825);
FORCEPROP 1 LAST MATERIAL X6S
J 0
(3016 1854);
DISPLAY 0.574468 (3016 1854);
PAINT GREEN (3016 1854);
DISPLAY INVISIBLE (3016 1854);
FORCEPROP 2 LAST VOLTAGE 6.3V
J 0
(3375 1825);
DISPLAY 0.553191 (3375 1825);
DISPLAY INVISIBLE (3375 1825);
FORCEPROP 1 LAST PIN_NAMES_ROTATE TRUE
J 0
(3025 1775);
DISPLAY 0.489362 (3025 1775);
PAINT GREEN (3025 1775);
DISPLAY INVISIBLE (3025 1775);
FORCEPROP 1 LAST PATH I77
J 0
(3025 1775);
DISPLAY 0.723404 (3025 1775);
DISPLAY INVISIBLE (3025 1775);
FORCEPROP 0 LAST CDS_LOCATION C2077
J 0
(3150 1800);
DISPLAY 1.021277 (3150 1800);
DISPLAY INVISIBLE (3150 1800);
FORCEPROP 0 LAST $SEC 1
J 0
(3150 1800);
DISPLAY 0.680851 (3150 1800);
PAINT MONO (3150 1800);
DISPLAY INVISIBLE (3150 1800);
FORCEPROP 0 LAST CDS_SEC 1
J 0
(3150 1800);
DISPLAY 1.021277 (3150 1800);
DISPLAY INVISIBLE (3150 1800);
FORCEADD Q_CAP..2
(3025 1825);
FORCEPROP 1 LAST PART_NUMBER CH4101KEE01
J 1
(3025 1875);
DISPLAY 0.638298 (3025 1875);
DISPLAY INVISIBLE (3025 1875);
FORCEPROP 1 LAST PACK_TYPE C0201
J 1
(3150 1825);
DISPLAY 0.404255 (3150 1825);
FORCEPROP 1 LAST MATERIAL X6S
J 0
(3225 1825);
DISPLAY 0.404255 (3225 1825);
FORCEPROP 1 LAST VALUE 0.1UF
J 2
(3400 1825);
DISPLAY 0.404255 (3400 1825);
FORCEPROP 1 LAST LOCATION C1097
J 1
(2850 1825);
DISPLAY 0.510638 (2850 1825);
FORCEPROP 1 LASTPIN (2925 1825) $PN 1
J 0
(2915 1840);
DISPLAY 0.787234 (2915 1840);
PAINT MONO (2915 1840);
FORCEPROP 1 LASTPIN (3125 1825) $PN 2
J 0
(3110 1840);
DISPLAY 0.787234 (3110 1840);
PAINT MONO (3110 1840);
FORCEPROP 2 LAST CDS_LIB pure_quanta
J 0
(3025 1825);
DISPLAY INVISIBLE (3025 1825);
FORCEPROP 1 LAST VOLTAGE 6.3V
J 0
(3025 1725);
DISPLAY 0.978723 (3025 1725);
DISPLAY INVISIBLE (3025 1725);
FORCEPROP 1 LAST TOLERANCE 10%
J 2
(3200 1825);
DISPLAY 0.978723 (3200 1825);
DISPLAY INVISIBLE (3200 1825);
FORCEPROP 1 LAST PATH I78
J 0
(3025 2025);
DISPLAY 0.978723 (3025 2025);
PAINT WHITE (3025 2025);
DISPLAY INVISIBLE (3025 2025);
FORCEPROP 0 LAST $SEC 1
J 0
(3400 1850);
DISPLAY 0.680851 (3400 1850);
PAINT MONO (3400 1850);
DISPLAY INVISIBLE (3400 1850);
FORCEPROP 2 LAST CDS_SEC 1
J 0
(3025 1875);
DISPLAY 1.021277 (3025 1875);
DISPLAY INVISIBLE (3025 1875);
FORCEADD Q_CAP_DIFFBUS..2
(3025 1925);
FORCEPROP 1 LAST PART_NUMBER SP_CH4221MEE01
J 0
(3141 2013);
DISPLAY 0.574468 (3141 2013);
PAINT GREEN (3141 2013);
DISPLAY INVISIBLE (3141 2013);
FORCEPROP 2 LAST VALUE DIFF BUS_0.22UF
J 0
(3150 1925);
DISPLAY 0.361702 (3150 1925);
FORCEPROP 1 LAST $LOCATION C2076
J 0
(2800 1950);
DISPLAY 0.489362 (2800 1950);
PAINT GREEN (2800 1950);
FORCEPROP 0 LASTPIN (2950 1925) $PN 1
J 2
(2940 1935);
DISPLAY 0.680851 (2940 1935);
PAINT MONO (2940 1935);
FORCEPROP 0 LASTPIN (3100 1925) $PN 2
J 0
(3110 1935);
DISPLAY 0.680851 (3110 1935);
PAINT MONO (3110 1935);
FORCEPROP 2 LAST CDS_LIB pure_quanta
J 0
(3025 1925);
DISPLAY INVISIBLE (3025 1925);
FORCEPROP 1 LAST CDS_LMAN_SYM_OUTLINE -25,50,25,-50
J 0
(3025 1925);
DISPLAY 0.468085 (3025 1925);
PAINT GREEN (3025 1925);
DISPLAY INVISIBLE (3025 1925);
FORCEPROP 2 LAST TOLERANCE 20%
J 0
(3100 1975);
DISPLAY 0.553191 (3100 1975);
DISPLAY INVISIBLE (3100 1975);
FORCEPROP 2 LAST PACK_TYPE C0201
J 0
(3200 1975);
DISPLAY 0.553191 (3200 1975);
DISPLAY INVISIBLE (3200 1975);
FORCEPROP 1 LAST MATERIAL X6S
J 0
(3016 2004);
DISPLAY 0.574468 (3016 2004);
PAINT GREEN (3016 2004);
DISPLAY INVISIBLE (3016 2004);
FORCEPROP 2 LAST VOLTAGE 6.3V
J 0
(3375 1975);
DISPLAY 0.553191 (3375 1975);
DISPLAY INVISIBLE (3375 1975);
FORCEPROP 1 LAST PIN_NAMES_ROTATE TRUE
J 0
(3025 1925);
DISPLAY 0.489362 (3025 1925);
PAINT GREEN (3025 1925);
DISPLAY INVISIBLE (3025 1925);
FORCEPROP 1 LAST PATH I79
J 0
(3025 1925);
DISPLAY 0.723404 (3025 1925);
DISPLAY INVISIBLE (3025 1925);
FORCEPROP 0 LAST CDS_LOCATION C2076
J 0
(3150 1950);
DISPLAY 1.021277 (3150 1950);
DISPLAY INVISIBLE (3150 1950);
FORCEPROP 0 LAST $SEC 1
J 0
(3150 1950);
DISPLAY 0.680851 (3150 1950);
PAINT MONO (3150 1950);
DISPLAY INVISIBLE (3150 1950);
FORCEPROP 0 LAST CDS_SEC 1
J 0
(3150 1950);
DISPLAY 1.021277 (3150 1950);
DISPLAY INVISIBLE (3150 1950);
FORCEADD OFFPAGE..1
(-2450 1325);
FORCEPROP 2 LAST $XR0 191 
J 0
(-2732 1325);
DISPLAY 0.638298 (-2732 1325);
PAINT MONO (-2732 1325);
FORCEPROP 1 LAST COMMENT_BODY TRUE
J 0
(-2325 1225);
DISPLAY 0.872340 (-2325 1225);
PAINT GREEN (-2325 1225);
DISPLAY INVISIBLE (-2325 1225);
FORCEPROP 1 LAST OFFPAGE TRUE
J 0
(-2125 1200);
DISPLAY 0.872340 (-2125 1200);
DISPLAY INVISIBLE (-2125 1200);
FORCEPROP 2 LAST CDS_LIB standard
J 0
(-2450 1325);
PAINT MONO (-2450 1325);
DISPLAY INVISIBLE (-2450 1325);
FORCEPROP 2 LAST PATH I8
J 0
(-2725 1375);
DISPLAY 1.021277 (-2725 1375);
DISPLAY INVISIBLE (-2725 1375);
FORCEADD Q_CAP..2
(3025 1875);
FORCEPROP 1 LAST PART_NUMBER CH4101KEE01
J 1
(3025 1925);
DISPLAY 0.638298 (3025 1925);
DISPLAY INVISIBLE (3025 1925);
FORCEPROP 1 LAST PACK_TYPE C0201
J 1
(3150 1875);
DISPLAY 0.404255 (3150 1875);
FORCEPROP 1 LAST VALUE 0.1UF
J 2
(3400 1875);
DISPLAY 0.404255 (3400 1875);
FORCEPROP 1 LAST MATERIAL X6S
J 0
(3225 1875);
DISPLAY 0.404255 (3225 1875);
FORCEPROP 1 LAST $LOCATION C1096
J 1
(2850 1875);
DISPLAY 0.510638 (2850 1875);
FORCEPROP 1 LASTPIN (2925 1875) $PN 1
J 0
(2915 1890);
DISPLAY 0.787234 (2915 1890);
PAINT MONO (2915 1890);
FORCEPROP 1 LASTPIN (3125 1875) $PN 2
J 0
(3110 1890);
DISPLAY 0.787234 (3110 1890);
PAINT MONO (3110 1890);
FORCEPROP 2 LAST CDS_LIB pure_quanta
J 0
(3025 1875);
DISPLAY INVISIBLE (3025 1875);
FORCEPROP 1 LAST VOLTAGE 6.3V
J 0
(3025 1775);
DISPLAY 0.978723 (3025 1775);
DISPLAY INVISIBLE (3025 1775);
FORCEPROP 1 LAST TOLERANCE 10%
J 2
(3200 1875);
DISPLAY 0.978723 (3200 1875);
DISPLAY INVISIBLE (3200 1875);
FORCEPROP 1 LAST PATH I80
J 0
(3025 2075);
DISPLAY 0.978723 (3025 2075);
PAINT WHITE (3025 2075);
DISPLAY INVISIBLE (3025 2075);
FORCEPROP 2 LAST CDS_LOCATION C1096
J 0
(3025 1925);
DISPLAY 1.021277 (3025 1925);
DISPLAY INVISIBLE (3025 1925);
FORCEPROP 0 LAST $SEC 1
J 0
(3400 1900);
DISPLAY 0.680851 (3400 1900);
PAINT MONO (3400 1900);
DISPLAY INVISIBLE (3400 1900);
FORCEPROP 2 LAST CDS_SEC 1
J 0
(3025 1925);
DISPLAY 1.021277 (3025 1925);
DISPLAY INVISIBLE (3025 1925);
FORCEADD Q_CAP_DIFFBUS..2
(3025 1975);
FORCEPROP 1 LAST PART_NUMBER SP_CH4221MEE01
J 0
(3141 2063);
DISPLAY 0.574468 (3141 2063);
PAINT GREEN (3141 2063);
DISPLAY INVISIBLE (3141 2063);
FORCEPROP 2 LAST VALUE DIFF BUS_0.22UF
J 0
(3150 1975);
DISPLAY 0.361702 (3150 1975);
FORCEPROP 1 LAST $LOCATION C2075
J 0
(2800 2000);
DISPLAY 0.489362 (2800 2000);
PAINT GREEN (2800 2000);
FORCEPROP 0 LASTPIN (2950 1975) $PN 1
J 2
(2940 1985);
DISPLAY 0.680851 (2940 1985);
PAINT MONO (2940 1985);
FORCEPROP 0 LASTPIN (3100 1975) $PN 2
J 0
(3110 1985);
DISPLAY 0.680851 (3110 1985);
PAINT MONO (3110 1985);
FORCEPROP 2 LAST CDS_LIB pure_quanta
J 0
(3025 1975);
DISPLAY INVISIBLE (3025 1975);
FORCEPROP 1 LAST CDS_LMAN_SYM_OUTLINE -25,50,25,-50
J 0
(3025 1975);
DISPLAY 0.468085 (3025 1975);
PAINT GREEN (3025 1975);
DISPLAY INVISIBLE (3025 1975);
FORCEPROP 2 LAST TOLERANCE 20%
J 0
(3100 2025);
DISPLAY 0.553191 (3100 2025);
DISPLAY INVISIBLE (3100 2025);
FORCEPROP 2 LAST PACK_TYPE C0201
J 0
(3200 2025);
DISPLAY 0.553191 (3200 2025);
DISPLAY INVISIBLE (3200 2025);
FORCEPROP 1 LAST MATERIAL X6S
J 0
(3016 2054);
DISPLAY 0.574468 (3016 2054);
PAINT GREEN (3016 2054);
DISPLAY INVISIBLE (3016 2054);
FORCEPROP 2 LAST VOLTAGE 6.3V
J 0
(3375 2025);
DISPLAY 0.553191 (3375 2025);
DISPLAY INVISIBLE (3375 2025);
FORCEPROP 1 LAST PIN_NAMES_ROTATE TRUE
J 0
(3025 1975);
DISPLAY 0.489362 (3025 1975);
PAINT GREEN (3025 1975);
DISPLAY INVISIBLE (3025 1975);
FORCEPROP 1 LAST PATH I81
J 0
(3025 1975);
DISPLAY 0.723404 (3025 1975);
DISPLAY INVISIBLE (3025 1975);
FORCEPROP 0 LAST CDS_LOCATION C2075
J 0
(3150 2000);
DISPLAY 1.021277 (3150 2000);
DISPLAY INVISIBLE (3150 2000);
FORCEPROP 0 LAST $SEC 1
J 0
(3150 2000);
DISPLAY 0.680851 (3150 2000);
PAINT MONO (3150 2000);
DISPLAY INVISIBLE (3150 2000);
FORCEPROP 0 LAST CDS_SEC 1
J 0
(3150 2000);
DISPLAY 1.021277 (3150 2000);
DISPLAY INVISIBLE (3150 2000);
FORCEADD Q_CAP_DIFFBUS..2
(3025 2025);
FORCEPROP 1 LAST PART_NUMBER SP_CH4221MEE01
J 0
(3141 2113);
DISPLAY 0.574468 (3141 2113);
PAINT GREEN (3141 2113);
DISPLAY INVISIBLE (3141 2113);
FORCEPROP 2 LAST VALUE DIFF BUS_0.22UF
J 0
(3150 2025);
DISPLAY 0.361702 (3150 2025);
FORCEPROP 1 LAST $LOCATION C2074
J 0
(2800 2050);
DISPLAY 0.489362 (2800 2050);
PAINT GREEN (2800 2050);
FORCEPROP 0 LASTPIN (2950 2025) $PN 1
J 2
(2940 2035);
DISPLAY 0.680851 (2940 2035);
PAINT MONO (2940 2035);
FORCEPROP 0 LASTPIN (3100 2025) $PN 2
J 0
(3110 2035);
DISPLAY 0.680851 (3110 2035);
PAINT MONO (3110 2035);
FORCEPROP 2 LAST CDS_LIB pure_quanta
J 0
(3025 2025);
DISPLAY INVISIBLE (3025 2025);
FORCEPROP 1 LAST CDS_LMAN_SYM_OUTLINE -25,50,25,-50
J 0
(3025 2025);
DISPLAY 0.468085 (3025 2025);
PAINT GREEN (3025 2025);
DISPLAY INVISIBLE (3025 2025);
FORCEPROP 2 LAST TOLERANCE 20%
J 0
(3100 2075);
DISPLAY 0.553191 (3100 2075);
DISPLAY INVISIBLE (3100 2075);
FORCEPROP 2 LAST PACK_TYPE C0201
J 0
(3200 2075);
DISPLAY 0.553191 (3200 2075);
DISPLAY INVISIBLE (3200 2075);
FORCEPROP 1 LAST MATERIAL X6S
J 0
(3016 2104);
DISPLAY 0.574468 (3016 2104);
PAINT GREEN (3016 2104);
DISPLAY INVISIBLE (3016 2104);
FORCEPROP 2 LAST VOLTAGE 6.3V
J 0
(3375 2075);
DISPLAY 0.553191 (3375 2075);
DISPLAY INVISIBLE (3375 2075);
FORCEPROP 1 LAST PIN_NAMES_ROTATE TRUE
J 0
(3025 2025);
DISPLAY 0.489362 (3025 2025);
PAINT GREEN (3025 2025);
DISPLAY INVISIBLE (3025 2025);
FORCEPROP 1 LAST PATH I82
J 0
(3025 2025);
DISPLAY 0.723404 (3025 2025);
DISPLAY INVISIBLE (3025 2025);
FORCEPROP 0 LAST CDS_LOCATION C2074
J 0
(3150 2050);
DISPLAY 1.021277 (3150 2050);
DISPLAY INVISIBLE (3150 2050);
FORCEPROP 0 LAST $SEC 1
J 0
(3150 2050);
DISPLAY 0.680851 (3150 2050);
PAINT MONO (3150 2050);
DISPLAY INVISIBLE (3150 2050);
FORCEPROP 0 LAST CDS_SEC 1
J 0
(3150 2050);
DISPLAY 1.021277 (3150 2050);
DISPLAY INVISIBLE (3150 2050);
FORCEADD Q_CAP_DIFFBUS..2
(3025 2075);
FORCEPROP 1 LAST PART_NUMBER SP_CH4221MEE01
J 0
(3141 2163);
DISPLAY 0.574468 (3141 2163);
PAINT GREEN (3141 2163);
DISPLAY INVISIBLE (3141 2163);
FORCEPROP 2 LAST VALUE DIFF BUS_0.22UF
J 0
(3150 2075);
DISPLAY 0.361702 (3150 2075);
FORCEPROP 1 LAST $LOCATION C2073
J 0
(2800 2100);
DISPLAY 0.489362 (2800 2100);
PAINT GREEN (2800 2100);
FORCEPROP 0 LASTPIN (2950 2075) $PN 1
J 2
(2940 2085);
DISPLAY 0.680851 (2940 2085);
PAINT MONO (2940 2085);
FORCEPROP 0 LASTPIN (3100 2075) $PN 2
J 0
(3110 2085);
DISPLAY 0.680851 (3110 2085);
PAINT MONO (3110 2085);
FORCEPROP 2 LAST CDS_LIB pure_quanta
J 0
(3025 2075);
DISPLAY INVISIBLE (3025 2075);
FORCEPROP 1 LAST CDS_LMAN_SYM_OUTLINE -25,50,25,-50
J 0
(3025 2075);
DISPLAY 0.468085 (3025 2075);
PAINT GREEN (3025 2075);
DISPLAY INVISIBLE (3025 2075);
FORCEPROP 2 LAST TOLERANCE 20%
J 0
(3100 2125);
DISPLAY 0.553191 (3100 2125);
DISPLAY INVISIBLE (3100 2125);
FORCEPROP 2 LAST PACK_TYPE C0201
J 0
(3200 2125);
DISPLAY 0.553191 (3200 2125);
DISPLAY INVISIBLE (3200 2125);
FORCEPROP 1 LAST MATERIAL X6S
J 0
(3016 2154);
DISPLAY 0.574468 (3016 2154);
PAINT GREEN (3016 2154);
DISPLAY INVISIBLE (3016 2154);
FORCEPROP 2 LAST VOLTAGE 6.3V
J 0
(3375 2125);
DISPLAY 0.553191 (3375 2125);
DISPLAY INVISIBLE (3375 2125);
FORCEPROP 1 LAST PIN_NAMES_ROTATE TRUE
J 0
(3025 2075);
DISPLAY 0.489362 (3025 2075);
PAINT GREEN (3025 2075);
DISPLAY INVISIBLE (3025 2075);
FORCEPROP 1 LAST PATH I83
J 0
(3025 2075);
DISPLAY 0.723404 (3025 2075);
DISPLAY INVISIBLE (3025 2075);
FORCEPROP 0 LAST CDS_LOCATION C2073
J 0
(3150 2100);
DISPLAY 1.021277 (3150 2100);
DISPLAY INVISIBLE (3150 2100);
FORCEPROP 0 LAST $SEC 1
J 0
(3150 2100);
DISPLAY 0.680851 (3150 2100);
PAINT MONO (3150 2100);
DISPLAY INVISIBLE (3150 2100);
FORCEPROP 0 LAST CDS_SEC 1
J 0
(3150 2100);
DISPLAY 1.021277 (3150 2100);
DISPLAY INVISIBLE (3150 2100);
FORCEADD OFFPAGE..2
(4300 925);
FORCEPROP 2 LAST $XR0 190 
J 0
(4489 925);
DISPLAY 0.638298 (4489 925);
PAINT MONO (4489 925);
FORCEPROP 2 LAST CDS_LIB standard
J 0
(4300 925);
PAINT MONO (4300 925);
DISPLAY INVISIBLE (4300 925);
FORCEPROP 1 LAST OFFPAGE TRUE
J 0
(4625 800);
DISPLAY 0.872340 (4625 800);
DISPLAY INVISIBLE (4625 800);
FORCEPROP 1 LAST COMMENT_BODY TRUE
J 0
(4255 830);
DISPLAY 0.872340 (4255 830);
PAINT GREEN (4255 830);
DISPLAY INVISIBLE (4255 830);
FORCEPROP 2 LAST PATH I84
J 0
(4500 975);
DISPLAY 1.021277 (4500 975);
DISPLAY INVISIBLE (4500 975);
FORCEADD OFFPAGE..2
(4300 1175);
FORCEPROP 2 LAST $XR0 190 
J 0
(4489 1175);
DISPLAY 0.638298 (4489 1175);
PAINT MONO (4489 1175);
FORCEPROP 2 LAST CDS_LIB standard
J 0
(4300 1175);
PAINT MONO (4300 1175);
DISPLAY INVISIBLE (4300 1175);
FORCEPROP 1 LAST OFFPAGE TRUE
J 0
(4625 1050);
DISPLAY 0.872340 (4625 1050);
DISPLAY INVISIBLE (4625 1050);
FORCEPROP 1 LAST COMMENT_BODY TRUE
J 0
(4255 1080);
DISPLAY 0.872340 (4255 1080);
PAINT GREEN (4255 1080);
DISPLAY INVISIBLE (4255 1080);
FORCEPROP 2 LAST PATH I85
J 0
(4500 1225);
DISPLAY 1.021277 (4500 1225);
DISPLAY INVISIBLE (4500 1225);
FORCEADD OFFPAGE..2
(4300 1125);
FORCEPROP 2 LAST $XR0 190 
J 0
(4489 1125);
DISPLAY 0.638298 (4489 1125);
PAINT MONO (4489 1125);
FORCEPROP 2 LAST CDS_LIB standard
J 0
(4300 1125);
PAINT MONO (4300 1125);
DISPLAY INVISIBLE (4300 1125);
FORCEPROP 1 LAST OFFPAGE TRUE
J 0
(4625 1000);
DISPLAY 0.872340 (4625 1000);
DISPLAY INVISIBLE (4625 1000);
FORCEPROP 1 LAST COMMENT_BODY TRUE
J 0
(4255 1030);
DISPLAY 0.872340 (4255 1030);
PAINT GREEN (4255 1030);
DISPLAY INVISIBLE (4255 1030);
FORCEPROP 2 LAST PATH I86
J 0
(4500 1175);
DISPLAY 1.021277 (4500 1175);
DISPLAY INVISIBLE (4500 1175);
FORCEADD OFFPAGE..2
(4300 1075);
FORCEPROP 2 LAST $XR0 190 
J 0
(4489 1075);
DISPLAY 0.638298 (4489 1075);
PAINT MONO (4489 1075);
FORCEPROP 2 LAST CDS_LIB standard
J 0
(4300 1075);
PAINT MONO (4300 1075);
DISPLAY INVISIBLE (4300 1075);
FORCEPROP 1 LAST OFFPAGE TRUE
J 0
(4625 950);
DISPLAY 0.872340 (4625 950);
DISPLAY INVISIBLE (4625 950);
FORCEPROP 1 LAST COMMENT_BODY TRUE
J 0
(4255 980);
DISPLAY 0.872340 (4255 980);
PAINT GREEN (4255 980);
DISPLAY INVISIBLE (4255 980);
FORCEPROP 2 LAST PATH I87
J 0
(4500 1125);
DISPLAY 1.021277 (4500 1125);
DISPLAY INVISIBLE (4500 1125);
FORCEADD OFFPAGE..2
(4300 1025);
FORCEPROP 2 LAST $XR0 190 
J 0
(4489 1025);
DISPLAY 0.638298 (4489 1025);
PAINT MONO (4489 1025);
FORCEPROP 2 LAST CDS_LIB standard
J 0
(4300 1025);
PAINT MONO (4300 1025);
DISPLAY INVISIBLE (4300 1025);
FORCEPROP 1 LAST OFFPAGE TRUE
J 0
(4625 900);
DISPLAY 0.872340 (4625 900);
DISPLAY INVISIBLE (4625 900);
FORCEPROP 1 LAST COMMENT_BODY TRUE
J 0
(4255 930);
DISPLAY 0.872340 (4255 930);
PAINT GREEN (4255 930);
DISPLAY INVISIBLE (4255 930);
FORCEPROP 2 LAST PATH I88
J 0
(4500 1075);
DISPLAY 1.021277 (4500 1075);
DISPLAY INVISIBLE (4500 1075);
FORCEADD OFFPAGE..2
(4300 975);
FORCEPROP 2 LAST $XR0 190 
J 0
(4489 975);
DISPLAY 0.638298 (4489 975);
PAINT MONO (4489 975);
FORCEPROP 2 LAST CDS_LIB standard
J 0
(4300 975);
PAINT MONO (4300 975);
DISPLAY INVISIBLE (4300 975);
FORCEPROP 1 LAST OFFPAGE TRUE
J 0
(4625 850);
DISPLAY 0.872340 (4625 850);
DISPLAY INVISIBLE (4625 850);
FORCEPROP 1 LAST COMMENT_BODY TRUE
J 0
(4255 880);
DISPLAY 0.872340 (4255 880);
PAINT GREEN (4255 880);
DISPLAY INVISIBLE (4255 880);
FORCEPROP 2 LAST PATH I89
J 0
(4500 1025);
DISPLAY 1.021277 (4500 1025);
DISPLAY INVISIBLE (4500 1025);
FORCEADD OFFPAGE..1
(-2450 1375);
FORCEPROP 2 LAST $XR0 191 
J 0
(-2732 1375);
DISPLAY 0.638298 (-2732 1375);
PAINT MONO (-2732 1375);
FORCEPROP 1 LAST COMMENT_BODY TRUE
J 0
(-2325 1275);
DISPLAY 0.872340 (-2325 1275);
PAINT GREEN (-2325 1275);
DISPLAY INVISIBLE (-2325 1275);
FORCEPROP 1 LAST OFFPAGE TRUE
J 0
(-2125 1250);
DISPLAY 0.872340 (-2125 1250);
DISPLAY INVISIBLE (-2125 1250);
FORCEPROP 2 LAST CDS_LIB standard
J 0
(-2450 1375);
PAINT MONO (-2450 1375);
DISPLAY INVISIBLE (-2450 1375);
FORCEPROP 2 LAST PATH I9
J 0
(-2725 1425);
DISPLAY 1.021277 (-2725 1425);
DISPLAY INVISIBLE (-2725 1425);
FORCEADD OFFPAGE..2
(4300 1325);
FORCEPROP 2 LAST $XR0 191 
J 0
(4489 1325);
DISPLAY 0.638298 (4489 1325);
PAINT MONO (4489 1325);
FORCEPROP 1 LAST COMMENT_BODY TRUE
J 0
(4255 1230);
DISPLAY 0.872340 (4255 1230);
PAINT GREEN (4255 1230);
DISPLAY INVISIBLE (4255 1230);
FORCEPROP 1 LAST OFFPAGE TRUE
J 0
(4625 1200);
DISPLAY 0.872340 (4625 1200);
DISPLAY INVISIBLE (4625 1200);
FORCEPROP 2 LAST CDS_LIB standard
J 0
(4300 1325);
PAINT MONO (4300 1325);
DISPLAY INVISIBLE (4300 1325);
FORCEPROP 2 LAST PATH I90
J 0
(4500 1375);
DISPLAY 1.021277 (4500 1375);
DISPLAY INVISIBLE (4500 1375);
FORCEADD OFFPAGE..2
(4300 1375);
FORCEPROP 2 LAST $XR0 191 
J 0
(4489 1375);
DISPLAY 0.638298 (4489 1375);
PAINT MONO (4489 1375);
FORCEPROP 1 LAST COMMENT_BODY TRUE
J 0
(4255 1280);
DISPLAY 0.872340 (4255 1280);
PAINT GREEN (4255 1280);
DISPLAY INVISIBLE (4255 1280);
FORCEPROP 1 LAST OFFPAGE TRUE
J 0
(4625 1250);
DISPLAY 0.872340 (4625 1250);
DISPLAY INVISIBLE (4625 1250);
FORCEPROP 2 LAST CDS_LIB standard
J 0
(4300 1375);
PAINT MONO (4300 1375);
DISPLAY INVISIBLE (4300 1375);
FORCEPROP 2 LAST PATH I91
J 0
(4500 1425);
DISPLAY 1.021277 (4500 1425);
DISPLAY INVISIBLE (4500 1425);
FORCEADD OFFPAGE..2
(4300 1425);
FORCEPROP 2 LAST $XR0 191 
J 0
(4489 1425);
DISPLAY 0.638298 (4489 1425);
PAINT MONO (4489 1425);
FORCEPROP 1 LAST COMMENT_BODY TRUE
J 0
(4255 1330);
DISPLAY 0.872340 (4255 1330);
PAINT GREEN (4255 1330);
DISPLAY INVISIBLE (4255 1330);
FORCEPROP 1 LAST OFFPAGE TRUE
J 0
(4625 1300);
DISPLAY 0.872340 (4625 1300);
DISPLAY INVISIBLE (4625 1300);
FORCEPROP 2 LAST CDS_LIB standard
J 0
(4300 1425);
PAINT MONO (4300 1425);
DISPLAY INVISIBLE (4300 1425);
FORCEPROP 2 LAST PATH I92
J 0
(4500 1475);
DISPLAY 1.021277 (4500 1475);
DISPLAY INVISIBLE (4500 1475);
FORCEADD OFFPAGE..2
(4300 1225);
FORCEPROP 2 LAST $XR0 190 
J 0
(4489 1225);
DISPLAY 0.638298 (4489 1225);
PAINT MONO (4489 1225);
FORCEPROP 2 LAST CDS_LIB standard
J 0
(4300 1225);
PAINT MONO (4300 1225);
DISPLAY INVISIBLE (4300 1225);
FORCEPROP 1 LAST OFFPAGE TRUE
J 0
(4625 1100);
DISPLAY 0.872340 (4625 1100);
DISPLAY INVISIBLE (4625 1100);
FORCEPROP 1 LAST COMMENT_BODY TRUE
J 0
(4255 1130);
DISPLAY 0.872340 (4255 1130);
PAINT GREEN (4255 1130);
DISPLAY INVISIBLE (4255 1130);
FORCEPROP 2 LAST PATH I93
J 0
(4500 1275);
DISPLAY 1.021277 (4500 1275);
DISPLAY INVISIBLE (4500 1275);
FORCEADD OFFPAGE..2
(4300 1275);
FORCEPROP 2 LAST $XR0 190 
J 0
(4489 1275);
DISPLAY 0.638298 (4489 1275);
PAINT MONO (4489 1275);
FORCEPROP 2 LAST CDS_LIB standard
J 0
(4300 1275);
PAINT MONO (4300 1275);
DISPLAY INVISIBLE (4300 1275);
FORCEPROP 1 LAST OFFPAGE TRUE
J 0
(4625 1150);
DISPLAY 0.872340 (4625 1150);
DISPLAY INVISIBLE (4625 1150);
FORCEPROP 1 LAST COMMENT_BODY TRUE
J 0
(4255 1180);
DISPLAY 0.872340 (4255 1180);
PAINT GREEN (4255 1180);
DISPLAY INVISIBLE (4255 1180);
FORCEPROP 2 LAST PATH I94
J 0
(4500 1325);
DISPLAY 1.021277 (4500 1325);
DISPLAY INVISIBLE (4500 1325);
FORCEADD OFFPAGE..2
(4300 1625);
FORCEPROP 2 LAST $XR0 191 
J 0
(4489 1625);
DISPLAY 0.638298 (4489 1625);
PAINT MONO (4489 1625);
FORCEPROP 1 LAST COMMENT_BODY TRUE
J 0
(4255 1530);
DISPLAY 0.872340 (4255 1530);
PAINT GREEN (4255 1530);
DISPLAY INVISIBLE (4255 1530);
FORCEPROP 1 LAST OFFPAGE TRUE
J 0
(4625 1500);
DISPLAY 0.872340 (4625 1500);
DISPLAY INVISIBLE (4625 1500);
FORCEPROP 2 LAST CDS_LIB standard
J 0
(4300 1625);
PAINT MONO (4300 1625);
DISPLAY INVISIBLE (4300 1625);
FORCEPROP 2 LAST PATH I95
J 0
(4500 1675);
DISPLAY 1.021277 (4500 1675);
DISPLAY INVISIBLE (4500 1675);
FORCEADD OFFPAGE..2
(4300 1675);
FORCEPROP 2 LAST $XR0 191 
J 0
(4489 1675);
DISPLAY 0.638298 (4489 1675);
PAINT MONO (4489 1675);
FORCEPROP 1 LAST COMMENT_BODY TRUE
J 0
(4255 1580);
DISPLAY 0.872340 (4255 1580);
PAINT GREEN (4255 1580);
DISPLAY INVISIBLE (4255 1580);
FORCEPROP 1 LAST OFFPAGE TRUE
J 0
(4625 1550);
DISPLAY 0.872340 (4625 1550);
DISPLAY INVISIBLE (4625 1550);
FORCEPROP 2 LAST CDS_LIB standard
J 0
(4300 1675);
PAINT MONO (4300 1675);
DISPLAY INVISIBLE (4300 1675);
FORCEPROP 2 LAST PATH I96
J 0
(4500 1725);
DISPLAY 1.021277 (4500 1725);
DISPLAY INVISIBLE (4500 1725);
FORCEADD OFFPAGE..2
(4300 1575);
FORCEPROP 2 LAST $XR0 191 
J 0
(4489 1575);
DISPLAY 0.638298 (4489 1575);
PAINT MONO (4489 1575);
FORCEPROP 1 LAST COMMENT_BODY TRUE
J 0
(4255 1480);
DISPLAY 0.872340 (4255 1480);
PAINT GREEN (4255 1480);
DISPLAY INVISIBLE (4255 1480);
FORCEPROP 1 LAST OFFPAGE TRUE
J 0
(4625 1450);
DISPLAY 0.872340 (4625 1450);
DISPLAY INVISIBLE (4625 1450);
FORCEPROP 2 LAST CDS_LIB standard
J 0
(4300 1575);
PAINT MONO (4300 1575);
DISPLAY INVISIBLE (4300 1575);
FORCEPROP 2 LAST PATH I97
J 0
(4500 1625);
DISPLAY 1.021277 (4500 1625);
DISPLAY INVISIBLE (4500 1625);
FORCEADD OFFPAGE..2
(4300 1475);
FORCEPROP 2 LAST $XR0 191 
J 0
(4489 1475);
DISPLAY 0.638298 (4489 1475);
PAINT MONO (4489 1475);
FORCEPROP 1 LAST COMMENT_BODY TRUE
J 0
(4255 1380);
DISPLAY 0.872340 (4255 1380);
PAINT GREEN (4255 1380);
DISPLAY INVISIBLE (4255 1380);
FORCEPROP 1 LAST OFFPAGE TRUE
J 0
(4625 1350);
DISPLAY 0.872340 (4625 1350);
DISPLAY INVISIBLE (4625 1350);
FORCEPROP 2 LAST CDS_LIB standard
J 0
(4300 1475);
PAINT MONO (4300 1475);
DISPLAY INVISIBLE (4300 1475);
FORCEPROP 2 LAST PATH I98
J 0
(4500 1525);
DISPLAY 1.021277 (4500 1525);
DISPLAY INVISIBLE (4500 1525);
FORCEADD OFFPAGE..2
(4300 1525);
FORCEPROP 2 LAST $XR0 191 
J 0
(4489 1525);
DISPLAY 0.638298 (4489 1525);
PAINT MONO (4489 1525);
FORCEPROP 1 LAST COMMENT_BODY TRUE
J 0
(4255 1430);
DISPLAY 0.872340 (4255 1430);
PAINT GREEN (4255 1430);
DISPLAY INVISIBLE (4255 1430);
FORCEPROP 1 LAST OFFPAGE TRUE
J 0
(4625 1400);
DISPLAY 0.872340 (4625 1400);
DISPLAY INVISIBLE (4625 1400);
FORCEPROP 2 LAST CDS_LIB standard
J 0
(4300 1525);
PAINT MONO (4300 1525);
DISPLAY INVISIBLE (4300 1525);
FORCEPROP 2 LAST PATH I99
J 0
(4500 1575);
DISPLAY 1.021277 (4500 1575);
DISPLAY INVISIBLE (4500 1575);
FORCEADD CAD_NOTE..1
(-2825 125);
FORCEPROP 1 LAST COMMENT_BODY TRUE
J 0
(-2800 225);
DISPLAY 0.978723 (-2800 225);
DISPLAY INVISIBLE (-2800 225);
FORCEPROP 2 LAST CDS_LIB logical_power
J 0
(-2825 125);
PAINT MONO (-2825 125);
DISPLAY INVISIBLE (-2825 125);
FORCEADD QUANTA_TITLE_BLOCK_C..1
(5125 -2050);
FORCEPROP 0 LAST CDS_CON_LAST_MODIFIED Fri Aug 25 14:02:53 2023
J 0
(3240 -2035);
PAINT MONO (3240 -2035);
DISPLAY INVISIBLE (3240 -2035);
FORCEPROP 1 LAST CUSTOM_TXT_CDS <CON_LAST_MODIFIED>
J 0
(3240 -2035);
DISPLAY 0.978723 (3240 -2035);
FORCEPROP 2 LAST CUSTOM_TXT_CDS <XR_PAGE_TITLE>
J 0
(-2765 3200);
DISPLAY 0.638298 (-2765 3200);
PAINT PINK (-2765 3200);
DISPLAY INVISIBLE (-2765 3200);
FORCEPROP 2 LAST CUSTOM_TXT_CDS <Q_REV>
J 0
(4941 -1947);
DISPLAY 1.212766 (4941 -1947);
FORCEPROP 2 LAST CUSTOM_TXT_CDS <NAME_2>
J 0
(1950 -2000);
FORCEPROP 2 LAST CUSTOM_TXT_CDS <NAME_1>
J 0
(1950 -1875);
FORCEPROP 2 LAST CUSTOM_TXT_CDS <Q_NUMBER>
J 0
(3722 -1947);
DISPLAY 1.212766 (3722 -1947);
FORCEPROP 2 LAST CUSTOM_TXT_CDS <CON_PAGE_NUM> OF <CON_TOTAL_PAGES>
J 0
(4679 -2032);
DISPLAY 0.978723 (4679 -2032);
FORCEPROP 2 LAST CUSTOM_TXT_CDS <Q_PROJ>
J 0
(2743 -1948);
DISPLAY 1.212766 (2743 -1948);
FORCEPROP 1 LAST Q_TITLE EMMITSBURG - DMI/SATA/PCIE (3/10)
J 0
(-4191 -2024);
DISPLAY 1.957447 (-4191 -2024);
PAINT GREEN (-4191 -2024);
FORCEPROP 1 LAST Q_DEPT 
J 1
(1362 -2001);
DISPLAY 1.957447 (1362 -2001);
PAINT GREEN (1362 -2001);
FORCEPROP 2 LAST CDS_XR_PAGE_TITLE CR-181 : @S9S_MB_2U_LIB.S9S_MB_2U(SCH_1):PAGE181
J 0
(-2765 3200);
DISPLAY 0.638298 (-2765 3200);
PAINT PINK (-2765 3200);
DISPLAY INVISIBLE (-2765 3200);
FORCEPROP 2 LAST CDS_LIB pure_quanta
J 0
(5125 -2050);
PAINT MONO (5125 -2050);
DISPLAY INVISIBLE (5125 -2050);
FORCEPROP 1 LAST CDS_LMAN_SYM_OUTLINE -9475,6775,100,-125
J 0
(5125 -2050);
DISPLAY 0.468085 (5125 -2050);
PAINT GREEN (5125 -2050);
DISPLAY INVISIBLE (5125 -2050);
FORCEPROP 2 LAST PAGE_BORDER TRUE
J 0
(-2765 3200);
DISPLAY 0.638298 (-2765 3200);
PAINT PINK (-2765 3200);
DISPLAY INVISIBLE (-2765 3200);
FORCEPROP 1 LAST COMMENT_BODY TRUE
J 0
(5137 -2063);
DISPLAY 0.978723 (5137 -2063);
PAINT GREEN (5137 -2063);
DISPLAY INVISIBLE (5137 -2063);
WIRE 17 -1 (-1675 2950)(-1675 2850);
WIRE 17 -1 (-1675 2950)(-1675 3050);
WIRE 17 -1 (-1675 2850)(-1675 2750);
WIRE 17 -1 (-1675 2750)(-1675 2650);
WIRE 17 -1 (-1675 3150)(-1675 3050);
WIRE 17 -1 (-1675 3250)(-1675 3150);
WIRE 17 -1 (-1675 3350)(-1675 3250);
WIRE 17 -1 (-1675 3350)(-2625 3350);
FORCEPROP 2 LAST SIG_NAME DMI_CPU0_PCH_TX_C_DP<7:0>
J 0
(-2560 3360);
DISPLAY 0.680851 (-2560 3360);
PAINT WHITE (-2560 3360);
WIRE 17 -1 (-1525 2800)(-1525 2700);
WIRE 17 -1 (-1525 2900)(-1525 2800);
WIRE 17 -1 (-1525 2700)(-1525 2600);
WIRE 17 -1 (-1525 2900)(-1525 3000);
WIRE 17 -1 (-1525 3000)(-1525 3100);
WIRE 17 -1 (-1525 3100)(-1525 3200);
WIRE 17 -1 (-1525 3200)(-1525 3300);
WIRE 17 -1 (-2625 3300)(-1525 3300);
FORCEPROP 2 LAST SIG_NAME DMI_CPU0_PCH_TX_C_DN<7:0>
J 0
(-2560 3310);
DISPLAY 0.680851 (-2560 3310);
PAINT WHITE (-2560 3310);
WIRE 17 -1 (2375 2700)(2375 2800);
WIRE 17 -1 (2375 2600)(2375 2700);
WIRE 17 -1 (2375 2800)(2375 2900);
WIRE 17 -1 (2375 2900)(2375 3000);
WIRE 17 -1 (2375 3000)(2375 3100);
WIRE 17 -1 (2375 3100)(2375 3200);
WIRE 17 -1 (2375 3200)(2375 3300);
WIRE 17 -1 (2375 3300)(3625 3300);
FORCEPROP 0 LAST SIG_NAME DMI_CPU0_PCH_RX_DN<7:0>
J 0
(2633 3306);
DISPLAY 0.680851 (2633 3306);
PAINT WHITE (2633 3306);
WIRE 17 -1 (2525 2650)(2525 2750);
WIRE 17 -1 (2525 2750)(2525 2850);
WIRE 17 -1 (2525 2850)(2525 2950);
WIRE 17 -1 (2525 2950)(2525 3050);
WIRE 17 -1 (2525 3050)(2525 3150);
WIRE 17 -1 (2525 3150)(2525 3250);
WIRE 17 -1 (2525 3250)(2525 3350);
WIRE 17 -1 (3625 3350)(2525 3350);
FORCEPROP 0 LAST SIG_NAME DMI_CPU0_PCH_RX_DP<7:0>
J 0
(2633 3356);
DISPLAY 0.680851 (2633 3356);
PAINT WHITE (2633 3356);
WIRE 16 -1 (1925 3025)(2425 3025);
WIRE 16 -1 (1925 3075)(2275 3075);
WIRE 16 -1 (3100 2075)(4250 2075);
FORCEPROP 2 LAST SIG_NAME P3E_PCH_NVS_TX_C_DP<1>
J 0
(3465 2085);
DISPLAY 0.680851 (3465 2085);
PAINT WHITE (3465 2085);
WIRE 16 -1 (3100 1975)(4250 1975);
FORCEPROP 2 LAST SIG_NAME P3E_PCH_NVS_TX_C_DP<0>
J 0
(3465 1985);
DISPLAY 0.680851 (3465 1985);
PAINT WHITE (3465 1985);
WIRE 16 -1 (3125 1875)(4250 1875);
FORCEPROP 2 LAST SIG_NAME USB3_PCH_TX_C_DP<4>
J 0
(3465 1885);
DISPLAY 0.680851 (3465 1885);
PAINT WHITE (3465 1885);
WIRE 16 -1 (3125 1825)(4250 1825);
FORCEPROP 2 LAST SIG_NAME USB3_PCH_TX_C_DN<4>
J 0
(3465 1835);
DISPLAY 0.680851 (3465 1835);
PAINT WHITE (3465 1835);
WIRE 16 -1 (3100 1925)(4250 1925);
FORCEPROP 2 LAST SIG_NAME P3E_PCH_NVS_TX_C_DN<0>
J 0
(3465 1935);
DISPLAY 0.680851 (3465 1935);
PAINT WHITE (3465 1935);
WIRE 16 -1 (3100 1775)(4250 1775);
FORCEPROP 2 LAST SIG_NAME P3E_PCH_BMC_TX_C_DP
J 0
(3465 1785);
DISPLAY 0.680851 (3465 1785);
PAINT WHITE (3465 1785);
WIRE 16 -1 (3100 1725)(4250 1725);
FORCEPROP 2 LAST SIG_NAME P3E_PCH_BMC_TX_C_DN
J 0
(3465 1735);
DISPLAY 0.680851 (3465 1735);
PAINT WHITE (3465 1735);
WIRE 16 -1 (3100 2025)(4250 2025);
FORCEPROP 2 LAST SIG_NAME P3E_PCH_NVS_TX_C_DN<1>
J 0
(3465 2035);
DISPLAY 0.680851 (3465 2035);
PAINT WHITE (3465 2035);
WIRE 16 -1 (3100 1625)(4250 1625);
FORCEPROP 2 LAST SIG_NAME P3E_PCH_E1S_TX_C_DN<3>
J 0
(3465 1635);
DISPLAY 0.680851 (3465 1635);
PAINT WHITE (3465 1635);
WIRE 16 -1 (3100 1675)(4250 1675);
FORCEPROP 2 LAST SIG_NAME P3E_PCH_E1S_TX_C_DP<3>
J 0
(3465 1685);
DISPLAY 0.680851 (3465 1685);
PAINT WHITE (3465 1685);
WIRE 16 -1 (3100 1575)(4250 1575);
FORCEPROP 2 LAST SIG_NAME P3E_PCH_E1S_TX_C_DP<2>
J 0
(3465 1585);
DISPLAY 0.680851 (3465 1585);
PAINT WHITE (3465 1585);
WIRE 16 -1 (3100 1425)(4250 1425);
FORCEPROP 2 LAST SIG_NAME P3E_PCH_E1S_TX_C_DN<1>
J 0
(3465 1435);
DISPLAY 0.680851 (3465 1435);
PAINT WHITE (3465 1435);
WIRE 16 -1 (3100 1375)(4250 1375);
FORCEPROP 2 LAST SIG_NAME P3E_PCH_E1S_TX_C_DP<0>
J 0
(3465 1385);
DISPLAY 0.680851 (3465 1385);
PAINT WHITE (3465 1385);
WIRE 16 -1 (3100 1125)(4250 1125);
FORCEPROP 2 LAST SIG_NAME P3E_PCH_M2_TX_C_DN<2>
J 0
(3465 1135);
DISPLAY 0.680851 (3465 1135);
PAINT WHITE (3465 1135);
WIRE 16 -1 (3100 1075)(4250 1075);
FORCEPROP 2 LAST SIG_NAME P3E_PCH_M2_TX_C_DP<1>
J 0
(3465 1085);
DISPLAY 0.680851 (3465 1085);
PAINT WHITE (3465 1085);
WIRE 16 -1 (3100 1225)(4250 1225);
FORCEPROP 2 LAST SIG_NAME P3E_PCH_M2_TX_C_DN<3>
J 0
(3465 1235);
DISPLAY 0.680851 (3465 1235);
PAINT WHITE (3465 1235);
WIRE 16 -1 (3100 1275)(4250 1275);
FORCEPROP 2 LAST SIG_NAME P3E_PCH_M2_TX_C_DP<3>
J 0
(3465 1285);
DISPLAY 0.680851 (3465 1285);
PAINT WHITE (3465 1285);
WIRE 16 -1 (3100 1475)(4250 1475);
FORCEPROP 2 LAST SIG_NAME P3E_PCH_E1S_TX_C_DP<1>
J 0
(3465 1485);
DISPLAY 0.680851 (3465 1485);
PAINT WHITE (3465 1485);
WIRE 16 -1 (3100 1525)(4250 1525);
FORCEPROP 2 LAST SIG_NAME P3E_PCH_E1S_TX_C_DN<2>
J 0
(3465 1535);
DISPLAY 0.680851 (3465 1535);
PAINT WHITE (3465 1535);
WIRE 16 -1 (3100 1325)(4250 1325);
FORCEPROP 2 LAST SIG_NAME P3E_PCH_E1S_TX_C_DN<0>
J 0
(3465 1335);
DISPLAY 0.680851 (3465 1335);
PAINT WHITE (3465 1335);
WIRE 16 -1 (3100 925)(4250 925);
FORCEPROP 2 LAST SIG_NAME P3E_PCH_M2_TX_C_DN<0>
J 0
(3465 935);
DISPLAY 0.680851 (3465 935);
PAINT WHITE (3465 935);
WIRE 16 -1 (3100 1025)(4250 1025);
FORCEPROP 2 LAST SIG_NAME P3E_PCH_M2_TX_C_DN<1>
J 0
(3465 1035);
DISPLAY 0.680851 (3465 1035);
PAINT WHITE (3465 1035);
WIRE 16 -1 (3100 1175)(4250 1175);
FORCEPROP 2 LAST SIG_NAME P3E_PCH_M2_TX_C_DP<2>
J 0
(3465 1185);
DISPLAY 0.680851 (3465 1185);
PAINT WHITE (3465 1185);
WIRE 16 -1 (3100 975)(4250 975);
FORCEPROP 2 LAST SIG_NAME P3E_PCH_M2_TX_C_DP<0>
J 0
(3465 985);
DISPLAY 0.680851 (3465 985);
PAINT WHITE (3465 985);
WIRE 16 -1 (1925 1775)(2950 1775);
FORCEPROP 2 LAST SIG_NAME P3E_PCH_BMC_TX_DP
J 0
(2115 1785);
DISPLAY 0.680851 (2115 1785);
PAINT WHITE (2115 1785);
WIRE 16 -1 (1925 1725)(2950 1725);
FORCEPROP 2 LAST SIG_NAME P3E_PCH_BMC_TX_DN
J 0
(2115 1735);
DISPLAY 0.680851 (2115 1735);
PAINT WHITE (2115 1735);
WIRE 16 -1 (1925 1675)(2950 1675);
FORCEPROP 2 LAST SIG_NAME P3E_PCH_E1S_TX_DP<3>
J 0
(2115 1685);
DISPLAY 0.680851 (2115 1685);
PAINT WHITE (2115 1685);
WIRE 16 -1 (1925 1575)(2950 1575);
FORCEPROP 2 LAST SIG_NAME P3E_PCH_E1S_TX_DP<2>
J 0
(2115 1585);
DISPLAY 0.680851 (2115 1585);
PAINT WHITE (2115 1585);
WIRE 16 -1 (1925 1625)(2950 1625);
FORCEPROP 2 LAST SIG_NAME P3E_PCH_E1S_TX_DN<3>
J 0
(2115 1635);
DISPLAY 0.680851 (2115 1635);
PAINT WHITE (2115 1635);
WIRE 16 -1 (1925 1025)(2950 1025);
FORCEPROP 2 LAST SIG_NAME P3E_PCH_M2_TX_DN<1>
J 0
(2115 1035);
DISPLAY 0.680851 (2115 1035);
PAINT WHITE (2115 1035);
WIRE 16 -1 (1925 1075)(2950 1075);
FORCEPROP 2 LAST SIG_NAME P3E_PCH_M2_TX_DP<1>
J 0
(2115 1085);
DISPLAY 0.680851 (2115 1085);
PAINT WHITE (2115 1085);
WIRE 16 -1 (1925 1125)(2950 1125);
FORCEPROP 2 LAST SIG_NAME P3E_PCH_M2_TX_DN<2>
J 0
(2115 1135);
DISPLAY 0.680851 (2115 1135);
PAINT WHITE (2115 1135);
WIRE 16 -1 (1925 1175)(2950 1175);
FORCEPROP 2 LAST SIG_NAME P3E_PCH_M2_TX_DP<2>
J 0
(2115 1185);
DISPLAY 0.680851 (2115 1185);
PAINT WHITE (2115 1185);
WIRE 16 -1 (1925 1275)(2950 1275);
FORCEPROP 2 LAST SIG_NAME P3E_PCH_M2_TX_DP<3>
J 0
(2115 1285);
DISPLAY 0.680851 (2115 1285);
PAINT WHITE (2115 1285);
WIRE 16 -1 (1925 1525)(2950 1525);
FORCEPROP 2 LAST SIG_NAME P3E_PCH_E1S_TX_DN<2>
J 0
(2115 1535);
DISPLAY 0.680851 (2115 1535);
PAINT WHITE (2115 1535);
WIRE 16 -1 (1925 1375)(2950 1375);
FORCEPROP 2 LAST SIG_NAME P3E_PCH_E1S_TX_DP<0>
J 0
(2115 1385);
DISPLAY 0.680851 (2115 1385);
PAINT WHITE (2115 1385);
WIRE 16 -1 (1925 1325)(2950 1325);
FORCEPROP 2 LAST SIG_NAME P3E_PCH_E1S_TX_DN<0>
J 0
(2115 1335);
DISPLAY 0.680851 (2115 1335);
PAINT WHITE (2115 1335);
WIRE 16 -1 (1925 1225)(2950 1225);
FORCEPROP 2 LAST SIG_NAME P3E_PCH_M2_TX_DN<3>
J 0
(2115 1235);
DISPLAY 0.680851 (2115 1235);
PAINT WHITE (2115 1235);
WIRE 16 -1 (1925 975)(2950 975);
FORCEPROP 2 LAST SIG_NAME P3E_PCH_M2_TX_DP<0>
J 0
(2115 985);
DISPLAY 0.680851 (2115 985);
PAINT WHITE (2115 985);
WIRE 16 -1 (1925 1475)(2950 1475);
FORCEPROP 2 LAST SIG_NAME P3E_PCH_E1S_TX_DP<1>
J 0
(2115 1485);
DISPLAY 0.680851 (2115 1485);
PAINT WHITE (2115 1485);
WIRE 16 -1 (1925 1425)(2950 1425);
FORCEPROP 2 LAST SIG_NAME P3E_PCH_E1S_TX_DN<1>
J 0
(2115 1435);
DISPLAY 0.680851 (2115 1435);
PAINT WHITE (2115 1435);
WIRE 16 -1 (1925 925)(2950 925);
FORCEPROP 2 LAST SIG_NAME P3E_PCH_M2_TX_DN<0>
J 0
(2115 935);
DISPLAY 0.680851 (2115 935);
PAINT WHITE (2115 935);
WIRE 16 -1 (2950 775)(1925 775);
FORCEPROP 2 LAST SIG_NAME NC_PCH_RSVD<10>
J 0
(2115 785);
DISPLAY 0.680851 (2115 785);
PAINT WHITE (2115 785);
WIRE 16 -1 (2950 825)(1925 825);
FORCEPROP 2 LAST SIG_NAME NC_PCH_RSVD<11>
J 0
(2115 835);
DISPLAY 0.680851 (2115 835);
PAINT WHITE (2115 835);
WIRE 16 -1 (1925 2175)(2950 2175);
FORCEPROP 2 LAST SIG_NAME TP_P3E_PCH_12_TX_DP
J 0
(2115 2185);
DISPLAY 0.680851 (2115 2185);
PAINT WHITE (2115 2185);
WIRE 16 -1 (1925 2125)(2950 2125);
FORCEPROP 2 LAST SIG_NAME TP_P3E_PCH_12_TX_DN
J 0
(2115 2135);
DISPLAY 0.680851 (2115 2135);
PAINT WHITE (2115 2135);
WIRE 16 -1 (1925 2225)(2950 2225);
FORCEPROP 2 LAST SIG_NAME TP_P3E_PCH_13_TX_DN
J 0
(2115 2235);
DISPLAY 0.680851 (2115 2235);
PAINT WHITE (2115 2235);
WIRE 16 -1 (1925 2275)(2950 2275);
FORCEPROP 2 LAST SIG_NAME TP_P3E_PCH_13_TX_DP
J 0
(2115 2285);
DISPLAY 0.680851 (2115 2285);
PAINT WHITE (2115 2285);
WIRE 16 -1 (1925 2075)(2950 2075);
FORCEPROP 2 LAST SIG_NAME P3E_PCH_NVS_TX_DP<1>
J 0
(2115 2085);
DISPLAY 0.680851 (2115 2085);
PAINT WHITE (2115 2085);
WIRE 16 -1 (1925 1975)(2950 1975);
FORCEPROP 2 LAST SIG_NAME P3E_PCH_NVS_TX_DP<0>
J 0
(2115 1985);
DISPLAY 0.680851 (2115 1985);
PAINT WHITE (2115 1985);
WIRE 16 -1 (1925 1925)(2950 1925);
FORCEPROP 2 LAST SIG_NAME P3E_PCH_NVS_TX_DN<0>
J 0
(2115 1935);
DISPLAY 0.680851 (2115 1935);
PAINT WHITE (2115 1935);
WIRE 16 -1 (1925 1825)(2925 1825);
FORCEPROP 2 LAST SIG_NAME USB3_PCH_TX_DN<4>
J 0
(2115 1835);
DISPLAY 0.680851 (2115 1835);
PAINT WHITE (2115 1835);
WIRE 16 -1 (1925 1875)(2925 1875);
FORCEPROP 2 LAST SIG_NAME USB3_PCH_TX_DP<4>
J 0
(2115 1885);
DISPLAY 0.680851 (2115 1885);
PAINT WHITE (2115 1885);
WIRE 16 -1 (1925 2025)(2950 2025);
FORCEPROP 2 LAST SIG_NAME P3E_PCH_NVS_TX_DN<1>
J 0
(2115 2035);
DISPLAY 0.680851 (2115 2035);
PAINT WHITE (2115 2035);
WIRE 16 -1 (1925 2475)(2950 2475);
FORCEPROP 2 LAST SIG_NAME TP_P3E_PCH_15_TX_DP
J 0
(2115 2485);
DISPLAY 0.680851 (2115 2485);
PAINT WHITE (2115 2485);
WIRE 16 -1 (1925 2375)(2950 2375);
FORCEPROP 2 LAST SIG_NAME TP_P3E_PCH_14_TX_DP
J 0
(2115 2385);
DISPLAY 0.680851 (2115 2385);
PAINT WHITE (2115 2385);
WIRE 16 -1 (1925 2325)(2950 2325);
FORCEPROP 2 LAST SIG_NAME TP_P3E_PCH_14_TX_DN
J 0
(2115 2335);
DISPLAY 0.680851 (2115 2335);
PAINT WHITE (2115 2335);
WIRE 16 -1 (1925 2425)(2950 2425);
FORCEPROP 2 LAST SIG_NAME TP_P3E_PCH_15_TX_DN
J 0
(2115 2435);
DISPLAY 0.680851 (2115 2435);
PAINT WHITE (2115 2435);
WIRE 16 -1 (1925 3275)(2275 3275);
WIRE 16 -1 (1925 3325)(2425 3325);
WIRE 16 -1 (1925 3175)(2275 3175);
WIRE 16 -1 (1925 3225)(2425 3225);
WIRE 16 -1 (1925 3125)(2425 3125);
WIRE 16 -1 (2275 2975)(1925 2975);
WIRE 16 -1 (1925 2875)(2275 2875);
WIRE 16 -1 (1925 2925)(2425 2925);
WIRE 16 -1 (1925 2775)(2275 2775);
WIRE 16 -1 (1925 2825)(2425 2825);
WIRE 16 -1 (1925 2725)(2425 2725);
WIRE 16 -1 (-1425 3275)(-1075 3275);
WIRE 16 -1 (-1425 2775)(-1075 2775);
WIRE 16 -1 (-1425 3075)(-1075 3075);
WIRE 16 -1 (-1425 3175)(-1075 3175);
WIRE 16 -1 (-1425 2975)(-1075 2975);
WIRE 16 -1 (-1425 2875)(-1075 2875);
WIRE 16 -1 (1925 2575)(2275 2575);
WIRE 16 -1 (1925 2625)(2425 2625);
WIRE 16 -1 (1925 2675)(2275 2675);
WIRE 16 -1 (-1425 2575)(-1075 2575);
WIRE 16 -1 (-1425 2675)(-1075 2675);
WIRE 16 -1 (-2400 1775)(-1075 1775);
FORCEPROP 2 LAST SIG_NAME P3E_PCH_BMC_RX_DP
J 0
(-2035 1785);
DISPLAY 0.680851 (-2035 1785);
PAINT WHITE (-2035 1785);
WIRE 16 -1 (-2400 1725)(-1075 1725);
FORCEPROP 2 LAST SIG_NAME P3E_PCH_BMC_RX_DN
J 0
(-2035 1735);
DISPLAY 0.680851 (-2035 1735);
PAINT WHITE (-2035 1735);
WIRE 16 -1 (-2400 1625)(-1075 1625);
FORCEPROP 2 LAST SIG_NAME P3E_PCH_E1S_RX_DN<3>
J 0
(-2035 1635);
DISPLAY 0.680851 (-2035 1635);
PAINT WHITE (-2035 1635);
WIRE 16 -1 (-2400 1675)(-1075 1675);
FORCEPROP 2 LAST SIG_NAME P3E_PCH_E1S_RX_DP<3>
J 0
(-2035 1685);
DISPLAY 0.680851 (-2035 1685);
PAINT WHITE (-2035 1685);
WIRE 16 -1 (-1075 675)(-2400 675);
FORCEPROP 2 LAST SIG_NAME NC_PCH_RSVD<8>
J 0
(-2035 685);
DISPLAY 0.680851 (-2035 685);
PAINT WHITE (-2035 685);
WIRE 16 -1 (-2400 1025)(-1075 1025);
FORCEPROP 2 LAST SIG_NAME P3E_PCH_M2_RX_DN<1>
J 0
(-2035 1035);
DISPLAY 0.680851 (-2035 1035);
PAINT WHITE (-2035 1035);
WIRE 16 -1 (-2400 1075)(-1075 1075);
FORCEPROP 2 LAST SIG_NAME P3E_PCH_M2_RX_DP<1>
J 0
(-2035 1085);
DISPLAY 0.680851 (-2035 1085);
PAINT WHITE (-2035 1085);
WIRE 16 -1 (-2400 1125)(-1075 1125);
FORCEPROP 2 LAST SIG_NAME P3E_PCH_M2_RX_DN<2>
J 0
(-2035 1135);
DISPLAY 0.680851 (-2035 1135);
PAINT WHITE (-2035 1135);
WIRE 16 -1 (-2400 925)(-1075 925);
FORCEPROP 2 LAST SIG_NAME P3E_PCH_M2_RX_DN<0>
J 0
(-2035 935);
DISPLAY 0.680851 (-2035 935);
PAINT WHITE (-2035 935);
WIRE 16 -1 (-2400 1225)(-1075 1225);
FORCEPROP 2 LAST SIG_NAME P3E_PCH_M2_RX_DN<3>
J 0
(-2035 1235);
DISPLAY 0.680851 (-2035 1235);
PAINT WHITE (-2035 1235);
WIRE 16 -1 (-2400 1175)(-1075 1175);
FORCEPROP 2 LAST SIG_NAME P3E_PCH_M2_RX_DP<2>
J 0
(-2035 1185);
DISPLAY 0.680851 (-2035 1185);
PAINT WHITE (-2035 1185);
WIRE 16 -1 (-2400 1275)(-1075 1275);
FORCEPROP 2 LAST SIG_NAME P3E_PCH_M2_RX_DP<3>
J 0
(-2035 1285);
DISPLAY 0.680851 (-2035 1285);
PAINT WHITE (-2035 1285);
WIRE 16 -1 (-2400 1325)(-1075 1325);
FORCEPROP 2 LAST SIG_NAME P3E_PCH_E1S_RX_DN<0>
J 0
(-2035 1335);
DISPLAY 0.680851 (-2035 1335);
PAINT WHITE (-2035 1335);
WIRE 16 -1 (-2400 1575)(-1075 1575);
FORCEPROP 2 LAST SIG_NAME P3E_PCH_E1S_RX_DP<2>
J 0
(-2035 1585);
DISPLAY 0.680851 (-2035 1585);
PAINT WHITE (-2035 1585);
WIRE 16 -1 (-2400 1375)(-1075 1375);
FORCEPROP 2 LAST SIG_NAME P3E_PCH_E1S_RX_DP<0>
J 0
(-2035 1385);
DISPLAY 0.680851 (-2035 1385);
PAINT WHITE (-2035 1385);
WIRE 16 -1 (-2400 1425)(-1075 1425);
FORCEPROP 2 LAST SIG_NAME P3E_PCH_E1S_RX_DN<1>
J 0
(-2035 1435);
DISPLAY 0.680851 (-2035 1435);
PAINT WHITE (-2035 1435);
WIRE 16 -1 (-2400 1475)(-1075 1475);
FORCEPROP 2 LAST SIG_NAME P3E_PCH_E1S_RX_DP<1>
J 0
(-2035 1485);
DISPLAY 0.680851 (-2035 1485);
PAINT WHITE (-2035 1485);
WIRE 16 -1 (-2400 975)(-1075 975);
FORCEPROP 2 LAST SIG_NAME P3E_PCH_M2_RX_DP<0>
J 0
(-2035 985);
DISPLAY 0.680851 (-2035 985);
PAINT WHITE (-2035 985);
WIRE 16 -1 (-2400 1525)(-1075 1525);
FORCEPROP 2 LAST SIG_NAME P3E_PCH_E1S_RX_DN<2>
J 0
(-2035 1535);
DISPLAY 0.680851 (-2035 1535);
PAINT WHITE (-2035 1535);
WIRE 16 -1 (-1075 725)(-2400 725);
FORCEPROP 2 LAST SIG_NAME NC_PCH_RSVD<9>
J 0
(-2035 735);
DISPLAY 0.680851 (-2035 735);
PAINT WHITE (-2035 735);
WIRE 16 -1 (-2400 2225)(-1075 2225);
FORCEPROP 2 LAST SIG_NAME TP_P3E_PCH_13_RX_DN
J 0
(-2035 2235);
DISPLAY 0.680851 (-2035 2235);
PAINT WHITE (-2035 2235);
WIRE 16 -1 (-2400 2125)(-1075 2125);
FORCEPROP 2 LAST SIG_NAME TP_P3E_PCH_12_RX_DN
J 0
(-2035 2135);
DISPLAY 0.680851 (-2035 2135);
PAINT WHITE (-2035 2135);
WIRE 16 -1 (-2400 2175)(-1075 2175);
FORCEPROP 2 LAST SIG_NAME TP_P3E_PCH_12_RX_DP
J 0
(-2035 2185);
DISPLAY 0.680851 (-2035 2185);
PAINT WHITE (-2035 2185);
WIRE 16 -1 (-2400 2275)(-1075 2275);
FORCEPROP 2 LAST SIG_NAME TP_P3E_PCH_13_RX_DP
J 0
(-2035 2285);
DISPLAY 0.680851 (-2035 2285);
PAINT WHITE (-2035 2285);
WIRE 16 -1 (-2400 2425)(-1075 2425);
FORCEPROP 2 LAST SIG_NAME TP_P3E_PCH_15_RX_DN
J 0
(-2035 2435);
DISPLAY 0.680851 (-2035 2435);
PAINT WHITE (-2035 2435);
WIRE 16 -1 (-2400 2375)(-1075 2375);
FORCEPROP 2 LAST SIG_NAME TP_P3E_PCH_14_RX_DP
J 0
(-2035 2385);
DISPLAY 0.680851 (-2035 2385);
PAINT WHITE (-2035 2385);
WIRE 16 -1 (-2400 2325)(-1075 2325);
FORCEPROP 2 LAST SIG_NAME TP_P3E_PCH_14_RX_DN
J 0
(-2035 2335);
DISPLAY 0.680851 (-2035 2335);
PAINT WHITE (-2035 2335);
WIRE 16 -1 (-2400 2075)(-1075 2075);
FORCEPROP 2 LAST SIG_NAME P3E_PCH_NVS_RX_DP<1>
J 0
(-2035 2085);
DISPLAY 0.680851 (-2035 2085);
PAINT WHITE (-2035 2085);
WIRE 16 -1 (-2400 2025)(-1075 2025);
FORCEPROP 2 LAST SIG_NAME P3E_PCH_NVS_RX_DN<1>
J 0
(-2035 2035);
DISPLAY 0.680851 (-2035 2035);
PAINT WHITE (-2035 2035);
WIRE 16 -1 (-1075 1825)(-2400 1825);
FORCEPROP 2 LAST SIG_NAME USB3_PCH_RX_BUF_DN<4>
J 0
(-2035 1835);
DISPLAY 0.553191 (-2035 1835);
PAINT WHITE (-2035 1835);
WIRE 16 -1 (-1075 1875)(-2400 1875);
FORCEPROP 2 LAST SIG_NAME USB3_PCH_RX_BUF_DP<4>
J 0
(-2035 1885);
DISPLAY 0.553191 (-2035 1885);
PAINT WHITE (-2035 1885);
WIRE 16 -1 (-2400 1925)(-1075 1925);
FORCEPROP 2 LAST SIG_NAME P3E_PCH_NVS_RX_DN<0>
J 0
(-2035 1935);
DISPLAY 0.680851 (-2035 1935);
PAINT WHITE (-2035 1935);
WIRE 16 -1 (-2400 1975)(-1075 1975);
FORCEPROP 2 LAST SIG_NAME P3E_PCH_NVS_RX_DP<0>
J 0
(-2035 1985);
DISPLAY 0.680851 (-2035 1985);
PAINT WHITE (-2035 1985);
WIRE 16 -1 (-2400 2475)(-1075 2475);
FORCEPROP 2 LAST SIG_NAME TP_P3E_PCH_15_RX_DP
J 0
(-2035 2485);
DISPLAY 0.680851 (-2035 2485);
PAINT WHITE (-2035 2485);
WIRE 16 -1 (-1575 2625)(-1075 2625);
WIRE 16 -1 (-1575 2725)(-1075 2725);
WIRE 16 -1 (-1575 2825)(-1075 2825);
WIRE 16 -1 (-1575 3325)(-1075 3325);
WIRE 16 -1 (-1575 3225)(-1075 3225);
WIRE 16 -1 (-1575 3125)(-1075 3125);
WIRE 16 -1 (-1575 3025)(-1075 3025);
WIRE 16 -1 (-1575 2925)(-1075 2925);
WIRE 16 -1 (-2975 650)(-2975 825);
WIRE 16 -1 (-1075 825)(-2975 825);
FORCEPROP 2 LAST SIG_NAME PCH_PCIEUP_RCOMPP
J 0
(-2035 835);
DISPLAY 0.680851 (-2035 835);
PAINT WHITE (-2035 835);
WIRE 16 -1 (-2975 450)(-2975 300);
WIRE 16 -1 (-2600 300)(-2975 300);
WIRE 16 -1 (-2600 775)(-2600 300);
WIRE 16 -1 (-2600 775)(-1075 775);
FORCEPROP 2 LAST SIG_NAME PCH_PCIEUP_RCOMPN
J 0
(-2035 785);
DISPLAY 0.680851 (-2035 785);
PAINT WHITE (-2035 785);
FORCENOTE
RCOMP RESISTOR PLACE IN TOP WITHIN 2 INCH
(-2975 -50) 0;
DISPLAY LEFT (-2975 -50);
DISPLAY 1.021277 (-2975 -50);
PAINT SKYBLUE (-2975 -50);
FORCENOTE
M.2
(4700 1200) 3;
DISPLAY LEFT (4700 1200);
DISPLAY 1.021277 (4700 1200);
PAINT SKYBLUE (4700 1200);
FORCENOTE
20210616 MODIFY FOR GT
(3050 2675) 0;
DISPLAY LEFT (3050 2675);
DISPLAY 1.595745 (3050 2675);
PAINT PINK (3050 2675);
QUIT
